G04 ================== begin FILE IDENTIFICATION RECORD ==================*
G04 Layout Name:  x887571-005_osp.brd*
G04 Film Name:    lyr5*
G04 File Format:  Gerber RS274X*
G04 File Origin:  Cadence Allegro 16.3-S036*
G04 Origin Date:  Thu Jul 03 00:06:57 2014*
G04 *
G04 Layer:  VIA CLASS/LYR5*
G04 Layer:  PIN/LYR5*
G04 Layer:  ETCH/LYR5*
G04 Layer:  DRAWING FORMAT/COMMON TEXT*
G04 Layer:  BOARD GEOMETRY/LAYER 5 TEXT*
G04 *
G04 Offset:    (0.0000 0.0000)*
G04 Mirror:    No*
G04 Mode:      Positive*
G04 Rotation:  0*
G04 FullContactRelief:  No*
G04 UndefLineWidth:     4.0000*
G04 ================== end FILE IDENTIFICATION RECORD ====================*
%FSLAX25Y25*MOIN*%
%IR0*IPPOS*OFA0.00000B0.00000*MIA0B0*SFA1.00000B1.00000*%
%ADD10C,.022*%
%ADD15C,.05*%
%ADD12C,.032*%
%ADD16C,.061*%
%ADD17C,.044*%
%ADD14C,.026*%
%ADD18C,.027*%
%ADD11C,.054*%
%ADD20C,.058*%
%ADD19C,.079*%
%ADD21C,.22*%
%ADD13C,.178*%
%ADD22C,.01*%
%ADD23C,.012*%
%ADD24C,.013*%
%ADD25C,.015*%
%ADD26C,.004*%
%ADD27C,.005*%
%ADD28C,.006*%
%ADD29C,.007*%
%ADD30C,.008*%
%ADD35C,.032*%
%ADD34C,.051*%
%ADD39C,.08*%
%ADD41C,.063*%
%ADD43C,.046*%
%ADD32C,.064*%
%ADD31C,.073*%
%ADD33C,.074*%
%ADD36C,.091001*%
%ADD44C,.091001*%
%ADD40C,.098*%
%ADD42C,.099*%
%ADD46C,.092914*%
%ADD47C,.092914*%
%ADD37C,.154001*%
%ADD38C,.186001*%
%ADD45C,.186001*%
G75*
%LPD*%
G75*
G36*
G01X-1625300Y-182700D02*
X-1625800Y-182200D01*
Y-150100D01*
X-1632400Y-143500D01*
X-1656700D01*
Y-87600D01*
X-1655800Y-86700D01*
X-1639300D01*
X-1639200Y-86600D01*
X-1633800D01*
X-1620077Y-72877D01*
G02X-1619408Y-72842I354J-354D01*
G03X-1617158Y-70592I1008J1242D01*
G02X-1617123Y-69923I388J315D01*
G01X-1611400Y-64200D01*
X-1481191D01*
G02X-1480691Y-64716I0J-500D01*
G03X-1472744Y-65477I3998J-124D01*
G02X-1471897Y-65203I494J-80D01*
G01X-1467600Y-69500D01*
X-1463300D01*
X-1462786Y-70014D01*
G02X-1462795Y-70730I-354J-354D01*
G03X-1460533Y-72992I1102J-1160D01*
G02X-1459817Y-72983I362J-344D01*
G01X-1457700Y-75100D01*
Y-181100D01*
X-1459050Y-182450D01*
X-1485348D01*
G02X-1485720Y-181616I0J500D01*
G03X-1491666I-2973J2676D01*
G02X-1492038Y-182450I-372J-334D01*
G01X-1499850D01*
X-1499900Y-182500D01*
X-1609700D01*
X-1609900Y-182700D01*
X-1625300D01*
G37*
G36*
G01X-1440341Y-14409D02*
Y9213D01*
G02X-1432598Y16955I7743J0D01*
G01X-417200D01*
Y-184750D01*
X-508000D01*
X-583900Y-184600D01*
X-585400D01*
X-585409Y-184591D01*
Y-69909D01*
X-606400Y-48918D01*
X-759000Y-48861D01*
X-763570Y-53430D01*
Y-179070D01*
X-765900Y-181400D01*
X-929600D01*
X-929950Y-181050D01*
Y-46850D01*
X-939900Y-36900D01*
X-951089D01*
G02X-951589Y-36399I0J500D01*
G03X-968489I-8450J23D01*
G02X-968989Y-36900I-500J-1D01*
G01X-994396D01*
G02X-994896Y-36399I0J500D01*
G03X-1011796I-8450J23D01*
G02X-1012296Y-36900I-500J-1D01*
G01X-1026270D01*
X-1026665Y-37295D01*
Y-37315D01*
X-1036900Y-47550D01*
Y-76492D01*
X-1037103Y-76531D01*
G03X-1037473Y-76636I427J-2209D01*
G02X-1038135Y-76293I-177J468D01*
G03X-1039359Y-73463I-9541J-2447D01*
G02X-1039162Y-72749I422J268D01*
G03X-1042246Y-69858I-1014J2009D01*
G02X-1042946Y-70100I-460J196D01*
G03X-1045229Y-69199I-4730J-8640D01*
G02X-1045572Y-68538I124J484D01*
G03X-1049780I-2104J797D01*
G02X-1050123Y-69199I-468J-177D01*
G03X-1052406Y-70100I2447J-9541D01*
G02X-1053106Y-69858I-240J439D01*
G03X-1056190Y-72749I-2070J-882D01*
G02X-1055993Y-73463I-225J-446D01*
G03X-1057217Y-76293I8317J-5277D01*
G02X-1057879Y-76636I-484J124D01*
G03Y-80844I-797J-2104D01*
G02X-1057217Y-81187I177J-468D01*
G03X-1056316Y-83470I9541J2447D01*
G02X-1056558Y-84170I-439J-240D01*
G03X-1053667Y-87254I882J-2070D01*
G02X-1052953Y-87057I446J-225D01*
G03X-1050123Y-88281I5277J8317D01*
G02X-1049780Y-88943I-124J-484D01*
G03X-1045572I2104J-797D01*
G02X-1045229Y-88281I468J177D01*
G03X-1042399Y-87057I-2447J9541D01*
G02X-1041685Y-87254I268J-422D01*
G03X-1038794Y-84170I2009J1014D01*
G02X-1039036Y-83470I196J460D01*
G03X-1038135Y-81187I-8640J4730D01*
G02X-1037473Y-80844I484J-124D01*
G03X-1037103Y-80949I797J2104D01*
G01X-1036900Y-80988D01*
Y-91400D01*
X-1043800Y-98300D01*
X-1082514D01*
G02X-1082815Y-97401I0J500D01*
G03X-1087460I-2323J3071D01*
G02X-1087762Y-98300I-302J-399D01*
G01X-1138616D01*
G02X-1138918Y-97401I0J500D01*
G03X-1143563I-2323J3071D01*
G02X-1143864Y-98300I-302J-399D01*
G01X-1168063D01*
G02X-1168511Y-97577I0J500D01*
G03X-1167283Y-92362I-10466J5215D01*
G01Y-80818D01*
G03X-1190669I-11693J12078D01*
G01Y-92362D01*
G03X-1189442Y-97577I11693J0D01*
G02X-1189890Y-98300I-448J-223D01*
G01X-1190000D01*
X-1203059Y-111359D01*
G02X-1203886Y-111165I-354J354D01*
G03X-1208579Y-116338I-3791J-1276D01*
G01X-1208509Y-116354D01*
X-1208282Y-116582D01*
X-1208535Y-116835D01*
X-1223755D01*
X-1235840Y-128920D01*
X-1256220D01*
X-1280150Y-152850D01*
Y-168172D01*
G02X-1280854Y-168629I-500J0D01*
G03Y-175938I-1627J-3654D01*
G02X-1280150Y-176395I203J-457D01*
G01Y-179144D01*
X-1280269Y-179217D01*
G03X-1280593Y-181677I840J-1362D01*
G01X-1280562Y-181711D01*
X-1280459Y-181959D01*
X-1283200Y-184700D01*
X-1455550D01*
Y-73450D01*
X-1461500Y-67500D01*
X-1467000D01*
X-1472200Y-62300D01*
X-1473603D01*
G03X-1479783I-3090J-2540D01*
G01X-1616914D01*
G03X-1619686I-1386J-800D01*
G01X-1620013D01*
G02X-1620227Y-61922I0J250D01*
G03X-1623130Y-60631I-1373J822D01*
G02X-1623961Y-60839I-478J146D01*
G01X-1626050Y-58750D01*
Y-45450D01*
X-1629389Y-42111D01*
X-1629403Y-42089D01*
G03X-1634451Y-37041I-14140J-9093D01*
G01X-1634473Y-37027D01*
X-1636400Y-35100D01*
X-1638643D01*
X-1638679Y-35089D01*
G03X-1648443Y-35100I-4865J-16092D01*
G01X-1661128D01*
Y16217D01*
X-1660255Y17090D01*
X-1625060D01*
X-1624187Y16217D01*
Y-18937D01*
G03X-1617231I3478J0D01*
G01Y16217D01*
X-1616367Y17080D01*
X-1461160D01*
Y17088D01*
X-1460289Y16217D01*
Y-14409D01*
G03X-1452283Y-22415I8006J0D01*
G01X-1448346D01*
G03X-1440341Y-14409I0J8006D01*
G37*
G36*
G01X-1277195Y-179595D02*
G03Y-176465I335J1565D01*
G02X-1277800Y-175977I-105J489D01*
G01Y-153400D01*
X-1254642Y-130242D01*
X-1235260D01*
X-1222853Y-117835D01*
X-1208121D01*
X-1208033Y-117748D01*
X-1205183D01*
X-1196500Y-109064D01*
X-1155498D01*
G03X-1153302I1098J1164D01*
G01X-1148100D01*
Y-184300D01*
X-1207300D01*
X-1217650Y-194650D01*
X-1268150D01*
X-1277800Y-185000D01*
Y-180083D01*
G02X-1277195Y-179595I500J0D01*
G37*
G36*
G01X-1033300Y-184300D02*
Y-130089D01*
X-1033157Y-130022D01*
G03Y-127130I-686J1446D01*
G01X-1033300Y-127063D01*
Y-109100D01*
X-1033500D01*
X-1033442Y-50942D01*
Y-48690D01*
X-1024472Y-39720D01*
X-1011106D01*
G03X-1004546Y-44740I7760J3345D01*
G02X-1004406Y-45688I-71J-495D01*
G01X-1004986Y-45958D01*
X-1005876Y-48545D01*
X-1004711Y-51043D01*
X-1003727Y-51451D01*
X-1000159Y-49787D01*
X-999840Y-48771D01*
X-1001004Y-46273D01*
X-1002432Y-45725D01*
G02X-1002314Y-44762I179J467D01*
G03X-995586Y-39720I-1033J8387D01*
G01X-967799D01*
G03X-961239Y-44740I7760J3345D01*
G02X-961099Y-45688I-71J-495D01*
G01X-961679Y-45958D01*
X-962569Y-48545D01*
X-961404Y-51043D01*
X-960420Y-51451D01*
X-956852Y-49787D01*
X-956533Y-48771D01*
X-957697Y-46273D01*
X-959125Y-45725D01*
G02X-959006Y-44762I179J467D01*
G03X-952279Y-39720I-1033J8387D01*
G01X-942780D01*
X-937100Y-45400D01*
X-937029Y-45371D01*
X-934700Y-47700D01*
Y-184300D01*
X-1033300D01*
G37*
G36*
G01X-895784Y-186850D02*
X-877784D01*
Y-184850D01*
X-895784D01*
X-903784D01*
Y-186850D01*
X-895784D01*
G37*
G36*
G01X-760200Y-137500D02*
Y-134349D01*
G02X-759957Y-134099I250J0D01*
G03Y-130901I-43J1599D01*
G02X-760200Y-130651I7J250D01*
G01Y-121849D01*
G02X-759957Y-121599I250J0D01*
G03Y-118401I-43J1599D01*
G02X-760200Y-118151I7J250D01*
G01Y-109349D01*
G02X-759957Y-109099I250J0D01*
G03Y-105901I-43J1599D01*
G02X-760200Y-105651I7J250D01*
G01Y-96849D01*
G02X-759957Y-96599I250J0D01*
G03Y-93401I-43J1599D01*
G02X-760200Y-93151I7J250D01*
G01Y-84349D01*
G02X-759957Y-84099I250J0D01*
G03Y-80901I-43J1599D01*
G02X-760200Y-80651I7J250D01*
G01Y-71849D01*
G02X-759957Y-71599I250J0D01*
G03Y-68401I-43J1599D01*
G02X-760200Y-68151I7J250D01*
G01Y-59349D01*
G02X-759957Y-59099I250J0D01*
G03Y-55901I-43J1599D01*
G02X-760200Y-55651I7J250D01*
G01Y-53700D01*
X-757500Y-51000D01*
X-615500D01*
X-613921Y-52579D01*
Y-73921D01*
X-614500Y-74500D01*
X-624000D01*
X-624500Y-75000D01*
Y-82000D01*
X-625200Y-82700D01*
X-627100D01*
X-646500Y-63300D01*
X-716300D01*
X-744100Y-91100D01*
Y-93149D01*
G02X-744814Y-93601I-500J0D01*
G03Y-98210I-1091J-2305D01*
G02X-744100Y-98662I214J-452D01*
G01Y-109684D01*
G02X-744814Y-110136I-500J0D01*
G03Y-114746I-1091J-2305D01*
G02X-744100Y-115197I214J-452D01*
G01Y-137500D01*
X-745402D01*
X-745426Y-137496D01*
G03X-746385I-480J-2504D01*
G01X-746409Y-137500D01*
X-760200D01*
G37*
G36*
G01X-735783Y-181700D02*
Y-179392D01*
G03Y-176986I-2248J1203D01*
G01Y-173880D01*
G03Y-171474I-2248J1203D01*
G01Y-169433D01*
X-740283D01*
Y-171480D01*
G03Y-173874I2252J-1197D01*
G01Y-176992D01*
G03X-740310Y-179334I2252J-1197D01*
G01X-740283Y-179387D01*
Y-180610D01*
G02X-741137Y-180963I-500J0D01*
G01X-742600Y-179500D01*
Y-93400D01*
X-714500Y-65300D01*
X-646700D01*
X-628000Y-84000D01*
X-624000D01*
X-623000Y-83000D01*
Y-76500D01*
X-622100Y-75600D01*
X-613560D01*
G02X-613097Y-76288I0J-500D01*
G03X-610132I1483J-602D01*
G02X-609668Y-75600I463J188D01*
G01X-608560D01*
G02X-608097Y-76288I0J-500D01*
G03X-605132I1483J-602D01*
G02X-604668Y-75600I463J188D01*
G01X-603560D01*
G02X-603097Y-76288I0J-500D01*
G03X-600132I1483J-602D01*
G02X-599668Y-75600I463J188D01*
G01X-598560D01*
G02X-598097Y-76288I0J-500D01*
G03X-595132I1483J-602D01*
G02X-594668Y-75600I463J188D01*
G01X-593560D01*
G02X-593097Y-76288I0J-500D01*
G03X-590291Y-75991I1483J-602D01*
G02X-590084Y-75600I207J141D01*
G01X-589500D01*
Y-177977D01*
G02X-590286Y-178387I-500J0D01*
G03X-592320Y-180843I-914J-1313D01*
G02X-592670Y-181700I-350J-357D01*
G01X-614723D01*
G02X-615155Y-180949I0J500D01*
G03X-622073I-3459J2009D01*
G02X-622505Y-181700I-432J-251D01*
G01X-672791D01*
Y-179392D01*
G03Y-176986I-2248J1203D01*
G01Y-173880D01*
G03Y-171474I-2248J1203D01*
G01Y-169433D01*
X-677291D01*
Y-171480D01*
G03Y-173874I2252J-1197D01*
G01Y-176992D01*
G03Y-179386I2252J-1197D01*
G01Y-181700D01*
X-688539D01*
Y-179392D01*
G03Y-176986I-2248J1203D01*
G01Y-173880D01*
G03Y-171474I-2248J1203D01*
G01Y-169433D01*
X-693039D01*
Y-171480D01*
G03Y-173874I2252J-1197D01*
G01Y-176992D01*
G03Y-179386I2252J-1197D01*
G01Y-181700D01*
X-704287D01*
Y-179392D01*
G03Y-176986I-2248J1203D01*
G01Y-173880D01*
G03Y-171474I-2248J1203D01*
G01Y-169433D01*
X-708787D01*
Y-171480D01*
G03Y-173874I2252J-1197D01*
G01Y-176992D01*
G03Y-179386I2252J-1197D01*
G01Y-181700D01*
X-720035D01*
Y-179392D01*
G03Y-176986I-2248J1203D01*
G01Y-173880D01*
G03Y-171474I-2248J1203D01*
G01Y-169433D01*
X-724535D01*
Y-171480D01*
G03Y-173874I2252J-1197D01*
G01Y-176992D01*
G03Y-179386I2252J-1197D01*
G01Y-181700D01*
X-735783D01*
G37*
G36*
G01X14500Y-138500D02*
X19000Y-143000D01*
Y-178000D01*
X14300Y-182700D01*
X-7539Y-184500D01*
X-336800D01*
X-339450Y-187150D01*
Y-187400D01*
X-346710Y-194660D01*
X-397319D01*
X-407420Y-184559D01*
X-414100Y-184600D01*
Y-102700D01*
X-414012Y-102488D01*
X-414300Y-102200D01*
Y15000D01*
X9000D01*
X14500Y9500D01*
Y-138500D01*
G37*
%LPC*%
G75*
G36*
G01X-1460090Y-81803D02*
Y-86977D01*
X-1460108Y-87106D01*
G02X-1463290Y-86800I-1585J216D01*
G01X-1463290Y-86793D01*
Y-81986D01*
X-1463290Y-81979D01*
G02X-1460108Y-81674I1598J90D01*
G01X-1460090Y-81803D01*
G37*
G36*
G01X-1470090D02*
Y-86977D01*
X-1470108Y-87106D01*
G02X-1473290Y-86800I-1585J216D01*
G01X-1473290Y-86793D01*
Y-81986D01*
X-1473290Y-81979D01*
G02X-1470108Y-81674I1598J90D01*
G01X-1470090Y-81803D01*
G37*
G36*
G01X-1480090D02*
Y-86977D01*
X-1480108Y-87106D01*
G02X-1483290Y-86800I-1585J216D01*
G01X-1483290Y-86793D01*
Y-81986D01*
X-1483290Y-81979D01*
G02X-1480108Y-81674I1598J90D01*
G01X-1480090Y-81803D01*
G37*
G36*
G01X-1465090Y-91803D02*
Y-96977D01*
X-1465108Y-97106D01*
G02X-1468290Y-96800I-1585J216D01*
G01X-1468290Y-96793D01*
Y-91986D01*
X-1468290Y-91979D01*
G02X-1465108Y-91674I1598J90D01*
G01X-1465090Y-91803D01*
G37*
G36*
G01X-1475090D02*
Y-96977D01*
X-1475108Y-97106D01*
G02X-1478290Y-96800I-1585J216D01*
G01X-1478290Y-96793D01*
Y-91986D01*
X-1478290Y-91979D01*
G02X-1475108Y-91674I1598J90D01*
G01X-1475090Y-91803D01*
G37*
G36*
G01X-1485090D02*
Y-96977D01*
X-1485108Y-97106D01*
G02X-1488290Y-96800I-1585J216D01*
G01X-1488290Y-96793D01*
Y-91986D01*
X-1488290Y-91979D01*
G02X-1485108Y-91674I1598J90D01*
G01X-1485090Y-91803D01*
G37*
G36*
G01X-1460090Y-101803D02*
Y-106977D01*
X-1460108Y-107106D01*
G02X-1463290Y-106800I-1585J216D01*
G01X-1463290Y-106793D01*
Y-101986D01*
X-1463290Y-101979D01*
G02X-1460108Y-101674I1598J90D01*
G01X-1460090Y-101803D01*
G37*
G36*
G01X-1470090D02*
Y-106977D01*
X-1470108Y-107106D01*
G02X-1473290Y-106800I-1585J216D01*
G01X-1473290Y-106793D01*
Y-101986D01*
X-1473290Y-101979D01*
G02X-1470108Y-101674I1598J90D01*
G01X-1470090Y-101803D01*
G37*
G36*
G01X-1480090D02*
Y-106977D01*
X-1480108Y-107106D01*
G02X-1483290Y-106800I-1585J216D01*
G01X-1483290Y-106793D01*
Y-101986D01*
X-1483290Y-101979D01*
G02X-1480108Y-101674I1598J90D01*
G01X-1480090Y-101803D01*
G37*
G36*
G01X-1550744Y-108132D02*
Y-110173D01*
X-1555244D01*
Y-108126D01*
G02Y-105732I2252J1197D01*
G01Y-102614D01*
G02Y-100221I2252J1197D01*
G01Y-98173D01*
X-1550744D01*
Y-100214D01*
G02Y-102621I-2248J-1203D01*
G01Y-105726D01*
G02Y-108132I-2248J-1203D01*
G37*
G36*
G01X-1566492D02*
Y-110173D01*
X-1570992D01*
Y-108126D01*
G02Y-105732I2252J1197D01*
G01Y-102614D01*
G02Y-100221I2252J1197D01*
G01Y-98173D01*
X-1566492D01*
Y-100214D01*
G02Y-102621I-2248J-1203D01*
G01Y-105726D01*
G02Y-108132I-2248J-1203D01*
G37*
G36*
G01X-1582240D02*
Y-110173D01*
X-1586740D01*
Y-108126D01*
G02Y-105732I2252J1197D01*
G01Y-102614D01*
G02Y-100221I2252J1197D01*
G01Y-98173D01*
X-1582240D01*
Y-100214D01*
G02Y-102621I-2248J-1203D01*
G01Y-105726D01*
G02Y-108132I-2248J-1203D01*
G37*
G36*
G01X-1597988D02*
Y-110173D01*
X-1602488D01*
Y-108126D01*
G02Y-105732I2252J1197D01*
G01Y-102614D01*
G02Y-100221I2252J1197D01*
G01Y-98173D01*
X-1597988D01*
Y-100214D01*
G02Y-102621I-2248J-1203D01*
G01Y-105726D01*
G02Y-108132I-2248J-1203D01*
G37*
G36*
G01X-1542870Y-113250D02*
Y-115291D01*
X-1547370D01*
Y-113244D01*
G02Y-110850I2252J1197D01*
G01Y-107732D01*
G02Y-105339I2252J1197D01*
G01Y-103291D01*
X-1542870D01*
Y-105332D01*
G02Y-107739I-2248J-1203D01*
G01Y-110844D01*
G02Y-113250I-2248J-1203D01*
G37*
G36*
G01X-1558618D02*
Y-115291D01*
X-1563118D01*
Y-113244D01*
G02Y-110850I2252J1197D01*
G01Y-107732D01*
G02Y-105339I2252J1197D01*
G01Y-103291D01*
X-1558618D01*
Y-105332D01*
G02Y-107739I-2248J-1203D01*
G01Y-110844D01*
G02Y-113250I-2248J-1203D01*
G37*
G36*
G01X-1574366D02*
Y-115291D01*
X-1578866D01*
Y-113244D01*
G02Y-110850I2252J1197D01*
G01Y-107732D01*
G02Y-105339I2252J1197D01*
G01Y-103291D01*
X-1574366D01*
Y-105332D01*
G02Y-107739I-2248J-1203D01*
G01Y-110844D01*
G02Y-113250I-2248J-1203D01*
G37*
G36*
G01X-1590114D02*
Y-115291D01*
X-1594614D01*
Y-113244D01*
G02Y-110850I2252J1197D01*
G01Y-107732D01*
G02Y-105339I2252J1197D01*
G01Y-103291D01*
X-1590114D01*
Y-105332D01*
G02Y-107739I-2248J-1203D01*
G01Y-110844D01*
G02Y-113250I-2248J-1203D01*
G37*
G36*
G01X-1465090Y-111803D02*
Y-116977D01*
X-1465108Y-117106D01*
G02X-1468290Y-116800I-1585J216D01*
G01X-1468290Y-116793D01*
Y-111986D01*
X-1468290Y-111979D01*
G02X-1465108Y-111674I1598J90D01*
G01X-1465090Y-111803D01*
G37*
G36*
G01X-1475090D02*
Y-116977D01*
X-1475108Y-117106D01*
G02X-1478290Y-116800I-1585J216D01*
G01X-1478290Y-116793D01*
Y-111986D01*
X-1478290Y-111979D01*
G02X-1475108Y-111674I1598J90D01*
G01X-1475090Y-111803D01*
G37*
G36*
G01X-1485090D02*
Y-116977D01*
X-1485108Y-117106D01*
G02X-1488290Y-116800I-1585J216D01*
G01X-1488290Y-116793D01*
Y-111986D01*
X-1488290Y-111979D01*
G02X-1485108Y-111674I1598J90D01*
G01X-1485090Y-111803D01*
G37*
G36*
G01X-1550744Y-124668D02*
Y-126709D01*
X-1555244D01*
Y-124661D01*
G02Y-122268I2252J1197D01*
G01Y-119150D01*
G02Y-116756I2252J1197D01*
G01Y-114709D01*
X-1550744D01*
Y-116750D01*
G02Y-119156I-2248J-1203D01*
G01Y-122261D01*
G02Y-124668I-2248J-1203D01*
G37*
G36*
G01X-1566492D02*
Y-126709D01*
X-1570992D01*
Y-124661D01*
G02Y-122268I2252J1197D01*
G01Y-119150D01*
G02Y-116756I2252J1197D01*
G01Y-114709D01*
X-1566492D01*
Y-116750D01*
G02Y-119156I-2248J-1203D01*
G01Y-122261D01*
G02Y-124668I-2248J-1203D01*
G37*
G36*
G01X-1582240D02*
Y-126709D01*
X-1586740D01*
Y-124661D01*
G02Y-122268I2252J1197D01*
G01Y-119150D01*
G02Y-116756I2252J1197D01*
G01Y-114709D01*
X-1582240D01*
Y-116750D01*
G02Y-119156I-2248J-1203D01*
G01Y-122261D01*
G02Y-124668I-2248J-1203D01*
G37*
G36*
G01X-1597988D02*
Y-126709D01*
X-1602488D01*
Y-124661D01*
G02Y-122268I2252J1197D01*
G01Y-119150D01*
G02Y-116756I2252J1197D01*
G01Y-114709D01*
X-1597988D01*
Y-116750D01*
G02Y-119156I-2248J-1203D01*
G01Y-122261D01*
G02Y-124668I-2248J-1203D01*
G37*
G36*
G01X-1460090Y-121803D02*
Y-126977D01*
X-1460108Y-127106D01*
G02X-1463290Y-126800I-1585J216D01*
G01X-1463290Y-126793D01*
Y-121986D01*
X-1463290Y-121979D01*
G02X-1460108Y-121674I1598J90D01*
G01X-1460090Y-121803D01*
G37*
G36*
G01X-1470090D02*
Y-126977D01*
X-1470108Y-127106D01*
G02X-1473290Y-126800I-1585J216D01*
G01X-1473290Y-126793D01*
Y-121986D01*
X-1473290Y-121979D01*
G02X-1470108Y-121674I1598J90D01*
G01X-1470090Y-121803D01*
G37*
G36*
G01X-1480090D02*
Y-126977D01*
X-1480108Y-127106D01*
G02X-1483290Y-126800I-1585J216D01*
G01X-1483290Y-126793D01*
Y-121986D01*
X-1483290Y-121979D01*
G02X-1480108Y-121674I1598J90D01*
G01X-1480090Y-121803D01*
G37*
G36*
G01X-1542870Y-129786D02*
Y-131827D01*
X-1547370D01*
Y-129779D01*
G02Y-127386I2252J1197D01*
G01Y-124268D01*
G02Y-121874I2252J1197D01*
G01Y-119827D01*
X-1542870D01*
Y-121868D01*
G02Y-124274I-2248J-1203D01*
G01Y-127379D01*
G02Y-129786I-2248J-1203D01*
G37*
G36*
G01X-1558618D02*
Y-131827D01*
X-1563118D01*
Y-129779D01*
G02Y-127386I2252J1197D01*
G01Y-124268D01*
G02Y-121874I2252J1197D01*
G01Y-119827D01*
X-1558618D01*
Y-121868D01*
G02Y-124274I-2248J-1203D01*
G01Y-127379D01*
G02Y-129786I-2248J-1203D01*
G37*
G36*
G01X-1574366D02*
Y-131827D01*
X-1578866D01*
Y-129779D01*
G02Y-127386I2252J1197D01*
G01Y-124268D01*
G02Y-121874I2252J1197D01*
G01Y-119827D01*
X-1574366D01*
Y-121868D01*
G02Y-124274I-2248J-1203D01*
G01Y-127379D01*
G02Y-129786I-2248J-1203D01*
G37*
G36*
G01X-1590114D02*
Y-131827D01*
X-1594614D01*
Y-129779D01*
G02Y-127386I2252J1197D01*
G01Y-124268D01*
G02Y-121874I2252J1197D01*
G01Y-119827D01*
X-1590114D01*
Y-121868D01*
G02Y-124274I-2248J-1203D01*
G01Y-127379D01*
G02Y-129786I-2248J-1203D01*
G37*
G36*
G01X-1605862D02*
Y-131827D01*
X-1610362D01*
Y-129779D01*
G02Y-127386I2252J1197D01*
G01Y-124268D01*
G02Y-121874I2252J1197D01*
G01Y-119827D01*
X-1605862D01*
Y-121868D01*
G02Y-124274I-2248J-1203D01*
G01Y-127379D01*
G02Y-129786I-2248J-1203D01*
G37*
G36*
G01X-1465090Y-131803D02*
Y-136977D01*
X-1465108Y-137106D01*
G02X-1468290Y-136800I-1585J216D01*
G01X-1468290Y-136793D01*
Y-131986D01*
X-1468290Y-131979D01*
G02X-1465108Y-131674I1598J90D01*
G01X-1465090Y-131803D01*
G37*
G36*
G01X-1475090D02*
Y-136977D01*
X-1475108Y-137106D01*
G02X-1478290Y-136800I-1585J216D01*
G01X-1478290Y-136793D01*
Y-131986D01*
X-1478290Y-131979D01*
G02X-1475108Y-131674I1598J90D01*
G01X-1475090Y-131803D01*
G37*
G36*
G01X-1485090D02*
Y-136977D01*
X-1485108Y-137106D01*
G02X-1488290Y-136800I-1585J216D01*
G01X-1488290Y-136793D01*
Y-131986D01*
X-1488290Y-131979D01*
G02X-1485108Y-131674I1598J90D01*
G01X-1485090Y-131803D01*
G37*
G36*
G01X-1550744Y-141203D02*
Y-143244D01*
X-1555244D01*
Y-141197D01*
G02Y-138803I2252J1197D01*
G01Y-135685D01*
G02Y-133291I2252J1197D01*
G01Y-131244D01*
X-1550744D01*
Y-133285D01*
G02Y-135691I-2248J-1203D01*
G01Y-138797D01*
G02Y-141203I-2248J-1203D01*
G37*
G36*
G01X-1566492D02*
Y-143244D01*
X-1570992D01*
Y-141197D01*
G02Y-138803I2252J1197D01*
G01Y-135685D01*
G02Y-133291I2252J1197D01*
G01Y-131244D01*
X-1566492D01*
Y-133285D01*
G02Y-135691I-2248J-1203D01*
G01Y-138797D01*
G02Y-141203I-2248J-1203D01*
G37*
G36*
G01X-1582240D02*
Y-143244D01*
X-1586740D01*
Y-141197D01*
G02Y-138803I2252J1197D01*
G01Y-135685D01*
G02Y-133291I2252J1197D01*
G01Y-131244D01*
X-1582240D01*
Y-133285D01*
G02Y-135691I-2248J-1203D01*
G01Y-138797D01*
G02Y-141203I-2248J-1203D01*
G37*
G36*
G01X-1597988D02*
Y-143244D01*
X-1602488D01*
Y-141197D01*
G02Y-138803I2252J1197D01*
G01Y-135685D01*
G02Y-133291I2252J1197D01*
G01Y-131244D01*
X-1597988D01*
Y-133285D01*
G02Y-135691I-2248J-1203D01*
G01Y-138797D01*
G02Y-141203I-2248J-1203D01*
G37*
G36*
G01X-1542870Y-146321D02*
Y-148362D01*
X-1547370D01*
Y-146315D01*
G02Y-143921I2252J1197D01*
G01Y-140803D01*
G02Y-138410I2252J1197D01*
G01Y-136362D01*
X-1542870D01*
Y-138403D01*
G02Y-140810I-2248J-1203D01*
G01Y-143915D01*
G02Y-146321I-2248J-1203D01*
G37*
G36*
G01X-1558618D02*
Y-148362D01*
X-1563118D01*
Y-146315D01*
G02Y-143921I2252J1197D01*
G01Y-140803D01*
G02Y-138410I2252J1197D01*
G01Y-136362D01*
X-1558618D01*
Y-138403D01*
G02Y-140810I-2248J-1203D01*
G01Y-143915D01*
G02Y-146321I-2248J-1203D01*
G37*
G36*
G01X-1574366D02*
Y-148362D01*
X-1578866D01*
Y-146315D01*
G02Y-143921I2252J1197D01*
G01Y-140803D01*
G02Y-138410I2252J1197D01*
G01Y-136362D01*
X-1574366D01*
Y-138403D01*
G02Y-140810I-2248J-1203D01*
G01Y-143915D01*
G02Y-146321I-2248J-1203D01*
G37*
G36*
G01X-1590114D02*
Y-148362D01*
X-1594614D01*
Y-146315D01*
G02Y-143921I2252J1197D01*
G01Y-140803D01*
G02Y-138410I2252J1197D01*
G01Y-136362D01*
X-1590114D01*
Y-138403D01*
G02Y-140810I-2248J-1203D01*
G01Y-143915D01*
G02Y-146321I-2248J-1203D01*
G37*
G36*
G01X-1605862D02*
Y-148362D01*
X-1610362D01*
Y-146315D01*
G02Y-143921I2252J1197D01*
G01Y-140803D01*
G02Y-138410I2252J1197D01*
G01Y-136362D01*
X-1605862D01*
Y-138403D01*
G02Y-140810I-2248J-1203D01*
G01Y-143915D01*
G02Y-146321I-2248J-1203D01*
G37*
G36*
G01X-1460090Y-141803D02*
Y-146977D01*
X-1460108Y-147106D01*
G02X-1463290Y-146800I-1585J216D01*
G01X-1463290Y-146793D01*
Y-141986D01*
X-1463290Y-141979D01*
G02X-1460108Y-141674I1598J90D01*
G01X-1460090Y-141803D01*
G37*
G36*
G01X-1470090D02*
Y-146977D01*
X-1470108Y-147106D01*
G02X-1473290Y-146800I-1585J216D01*
G01X-1473290Y-146793D01*
Y-141986D01*
X-1473290Y-141979D01*
G02X-1470108Y-141674I1598J90D01*
G01X-1470090Y-141803D01*
G37*
G36*
G01X-1480090D02*
Y-146977D01*
X-1480108Y-147106D01*
G02X-1483290Y-146800I-1585J216D01*
G01X-1483290Y-146793D01*
Y-141986D01*
X-1483290Y-141979D01*
G02X-1480108Y-141674I1598J90D01*
G01X-1480090Y-141803D01*
G37*
G36*
G01X-1465090Y-151803D02*
Y-156977D01*
X-1465108Y-157106D01*
G02X-1468290Y-156800I-1585J216D01*
G01X-1468290Y-156793D01*
Y-151986D01*
X-1468290Y-151979D01*
G02X-1465108Y-151674I1598J90D01*
G01X-1465090Y-151803D01*
G37*
G36*
G01X-1475090D02*
Y-156977D01*
X-1475108Y-157106D01*
G02X-1478290Y-156800I-1585J216D01*
G01X-1478290Y-156793D01*
Y-151986D01*
X-1478290Y-151979D01*
G02X-1475108Y-151674I1598J90D01*
G01X-1475090Y-151803D01*
G37*
G36*
G01X-1485090D02*
Y-156977D01*
X-1485108Y-157106D01*
G02X-1488290Y-156800I-1585J216D01*
G01X-1488290Y-156793D01*
Y-151986D01*
X-1488290Y-151979D01*
G02X-1485108Y-151674I1598J90D01*
G01X-1485090Y-151803D01*
G37*
G36*
G01X-1550744Y-157739D02*
Y-159780D01*
X-1555244D01*
Y-157732D01*
G02Y-155339I2252J1197D01*
G01Y-152220D01*
G02Y-149827I2252J1197D01*
G01Y-147780D01*
X-1550744D01*
Y-149820D01*
G02Y-152227I-2248J-1203D01*
G01Y-155332D01*
G02Y-157739I-2248J-1203D01*
G37*
G36*
G01X-1566492D02*
Y-159780D01*
X-1570992D01*
Y-157732D01*
G02Y-155339I2252J1197D01*
G01Y-152220D01*
G02Y-149827I2252J1197D01*
G01Y-147780D01*
X-1566492D01*
Y-149820D01*
G02Y-152227I-2248J-1203D01*
G01Y-155332D01*
G02Y-157739I-2248J-1203D01*
G37*
G36*
G01X-1582240D02*
Y-159780D01*
X-1586740D01*
Y-157732D01*
G02Y-155339I2252J1197D01*
G01Y-152220D01*
G02Y-149827I2252J1197D01*
G01Y-147780D01*
X-1582240D01*
Y-149820D01*
G02Y-152227I-2248J-1203D01*
G01Y-155332D01*
G02Y-157739I-2248J-1203D01*
G37*
G36*
G01X-1597988D02*
Y-159780D01*
X-1602488D01*
Y-157732D01*
G02Y-155339I2252J1197D01*
G01Y-152220D01*
G02Y-149827I2252J1197D01*
G01Y-147780D01*
X-1597988D01*
Y-149820D01*
G02Y-152227I-2248J-1203D01*
G01Y-155332D01*
G02Y-157739I-2248J-1203D01*
G37*
G36*
G01X-1542870Y-162857D02*
Y-164898D01*
X-1547370D01*
Y-162850D01*
G02Y-160457I2252J1197D01*
G01Y-157339D01*
G02Y-154945I2252J1197D01*
G01Y-152898D01*
X-1542870D01*
Y-154939D01*
G02Y-157345I-2248J-1203D01*
G01Y-160450D01*
G02Y-162857I-2248J-1203D01*
G37*
G36*
G01X-1558618D02*
Y-164898D01*
X-1563118D01*
Y-162850D01*
G02Y-160457I2252J1197D01*
G01Y-157339D01*
G02Y-154945I2252J1197D01*
G01Y-152898D01*
X-1558618D01*
Y-154939D01*
G02Y-157345I-2248J-1203D01*
G01Y-160450D01*
G02Y-162857I-2248J-1203D01*
G37*
G36*
G01X-1574366D02*
Y-164898D01*
X-1578866D01*
Y-162850D01*
G02Y-160457I2252J1197D01*
G01Y-157339D01*
G02Y-154945I2252J1197D01*
G01Y-152898D01*
X-1574366D01*
Y-154939D01*
G02Y-157345I-2248J-1203D01*
G01Y-160450D01*
G02Y-162857I-2248J-1203D01*
G37*
G36*
G01X-1590114D02*
Y-164898D01*
X-1594614D01*
Y-162850D01*
G02Y-160457I2252J1197D01*
G01Y-157339D01*
G02Y-154945I2252J1197D01*
G01Y-152898D01*
X-1590114D01*
Y-154939D01*
G02Y-157345I-2248J-1203D01*
G01Y-160450D01*
G02Y-162857I-2248J-1203D01*
G37*
G36*
G01X-1605862D02*
Y-164898D01*
X-1610362D01*
Y-162850D01*
G02Y-160457I2252J1197D01*
G01Y-157339D01*
G02Y-154945I2252J1197D01*
G01Y-152898D01*
X-1605862D01*
Y-154939D01*
G02Y-157345I-2248J-1203D01*
G01Y-160450D01*
G02Y-162857I-2248J-1203D01*
G37*
G36*
G01X-1460090Y-161803D02*
Y-166977D01*
X-1460108Y-167106D01*
G02X-1463290Y-166800I-1585J216D01*
G01X-1463290Y-166793D01*
Y-161986D01*
X-1463290Y-161979D01*
G02X-1460108Y-161674I1598J90D01*
G01X-1460090Y-161803D01*
G37*
G36*
G01X-1470090D02*
Y-166977D01*
X-1470108Y-167106D01*
G02X-1473290Y-166800I-1585J216D01*
G01X-1473290Y-166793D01*
Y-161986D01*
X-1473290Y-161979D01*
G02X-1470108Y-161674I1598J90D01*
G01X-1470090Y-161803D01*
G37*
G36*
G01X-1480090D02*
Y-166977D01*
X-1480108Y-167106D01*
G02X-1483290Y-166800I-1585J216D01*
G01X-1483290Y-166793D01*
Y-161986D01*
X-1483290Y-161979D01*
G02X-1480108Y-161674I1598J90D01*
G01X-1480090Y-161803D01*
G37*
G36*
G01X-1550744Y-174274D02*
Y-176315D01*
X-1555244D01*
Y-174268D01*
G02Y-171874I2252J1197D01*
G01Y-168756D01*
G02Y-166362I2252J1197D01*
G01Y-164315D01*
X-1550744D01*
Y-166356D01*
G02Y-168762I-2248J-1203D01*
G01Y-171868D01*
G02Y-174274I-2248J-1203D01*
G37*
G36*
G01X-1566492D02*
Y-176315D01*
X-1570992D01*
Y-174268D01*
G02Y-171874I2252J1197D01*
G01Y-168756D01*
G02Y-166362I2252J1197D01*
G01Y-164315D01*
X-1566492D01*
Y-166356D01*
G02Y-168762I-2248J-1203D01*
G01Y-171868D01*
G02Y-174274I-2248J-1203D01*
G37*
G36*
G01X-1582240D02*
Y-176315D01*
X-1586740D01*
Y-174268D01*
G02Y-171874I2252J1197D01*
G01Y-168756D01*
G02Y-166362I2252J1197D01*
G01Y-164315D01*
X-1582240D01*
Y-166356D01*
G02Y-168762I-2248J-1203D01*
G01Y-171868D01*
G02Y-174274I-2248J-1203D01*
G37*
G36*
G01X-1597988D02*
Y-176315D01*
X-1602488D01*
Y-174268D01*
G02Y-171874I2252J1197D01*
G01Y-168756D01*
G02Y-166362I2252J1197D01*
G01Y-164315D01*
X-1597988D01*
Y-166356D01*
G02Y-168762I-2248J-1203D01*
G01Y-171868D01*
G02Y-174274I-2248J-1203D01*
G37*
G36*
G01X-1613736D02*
Y-176315D01*
X-1618236D01*
Y-174268D01*
G02Y-171874I2252J1197D01*
G01Y-168756D01*
G02Y-166362I2252J1197D01*
G01Y-164315D01*
X-1613736D01*
Y-166356D01*
G02Y-168762I-2248J-1203D01*
G01Y-171868D01*
G02Y-174274I-2248J-1203D01*
G37*
G36*
G01X-1542870Y-179392D02*
Y-181433D01*
X-1547370D01*
Y-179386D01*
G02Y-176992I2252J1197D01*
G01Y-173874D01*
G02Y-171480I2252J1197D01*
G01Y-169433D01*
X-1542870D01*
Y-171474D01*
G02Y-173880I-2248J-1203D01*
G01Y-176986D01*
G02Y-179392I-2248J-1203D01*
G37*
G36*
G01X-1558618D02*
Y-181433D01*
X-1563118D01*
Y-179386D01*
G02Y-176992I2252J1197D01*
G01Y-173874D01*
G02Y-171480I2252J1197D01*
G01Y-169433D01*
X-1558618D01*
Y-171474D01*
G02Y-173880I-2248J-1203D01*
G01Y-176986D01*
G02Y-179392I-2248J-1203D01*
G37*
G36*
G01X-1574366D02*
Y-181433D01*
X-1578866D01*
Y-179386D01*
G02Y-176992I2252J1197D01*
G01Y-173874D01*
G02Y-171480I2252J1197D01*
G01Y-169433D01*
X-1574366D01*
Y-171474D01*
G02Y-173880I-2248J-1203D01*
G01Y-176986D01*
G02Y-179392I-2248J-1203D01*
G37*
G36*
G01X-1590114D02*
Y-181433D01*
X-1594614D01*
Y-179386D01*
G02Y-176992I2252J1197D01*
G01Y-173874D01*
G02Y-171480I2252J1197D01*
G01Y-169433D01*
X-1590114D01*
Y-171474D01*
G02Y-173880I-2248J-1203D01*
G01Y-176986D01*
G02Y-179392I-2248J-1203D01*
G37*
G36*
G01X-1605862D02*
Y-181433D01*
X-1610362D01*
Y-179386D01*
G02Y-176992I2252J1197D01*
G01Y-173874D01*
G02Y-171480I2252J1197D01*
G01Y-169433D01*
X-1605862D01*
Y-171474D01*
G02Y-173880I-2248J-1203D01*
G01Y-176986D01*
G02Y-179392I-2248J-1203D01*
G37*
G36*
G01X-1614892Y-104625D02*
G02X-1617077I-1093J-2304D01*
G03Y-103721I-214J452D01*
G02X-1614892I1093J2304D01*
G03Y-104625I214J-452D01*
G37*
G36*
G01Y-132184D02*
G02X-1617077I-1093J-2304D01*
G03Y-131280I-214J452D01*
G02Y-126672I1093J2304D01*
G03Y-125769I-214J452D01*
G02Y-121160I1093J2304D01*
G03Y-120257I-214J452D01*
G02X-1614892I1093J2304D01*
G03Y-121160I214J-452D01*
G02Y-125769I-1093J-2304D01*
G03Y-126672I214J-452D01*
G02Y-131280I-1093J-2304D01*
G03Y-132184I214J-452D01*
G37*
G36*
G01X-490095Y-158465D02*
G03X-490143Y-157514I-177J468D01*
G02X-483477I3333J12514D01*
G03X-483525Y-158465I129J-483D01*
G02X-490095I-3285J-8701D01*
G37*
G36*
G01X-549173Y-104441D02*
Y-115984D01*
G02X-572559I-11693J0D01*
G01Y-104441D01*
G02X-549173I11693J12078D01*
G37*
G36*
G01X-1411378Y-134126D02*
Y-145669D01*
G02X-1434764I-11693J0D01*
G01Y-134126D01*
G02X-1411378I11693J12078D01*
G37*
G36*
G01X-1347998Y-116208D02*
G02X-1347689Y-120301I-8891J-2729D01*
G02X-1347998Y-116208I-9199J1364D01*
G37*
G36*
G01X-1450413Y-73798D02*
G02X-1451378Y-72526I-1587J-202D01*
G03X-1450687Y-72002I194J461D01*
G02X-1450693Y-71655I1587J202D01*
G03X-1451336Y-71131I-498J45D01*
G02X-1451114Y-68154I-464J1531D01*
G03X-1450400Y-67702I214J452D01*
G02X-1450399Y-67655I1600J2D01*
G03X-1451090Y-67179I-500J14D01*
G02X-1451090Y-64221I-610J1479D01*
G03X-1450400Y-63768I191J462D01*
G02X-1450366Y-63473I1600J-32D01*
G03X-1450731Y-63203I-245J51D01*
G02X-1450966Y-60292I-769J1403D01*
G03X-1450299Y-59840I167J471D01*
G02X-1449234Y-61408I1599J-60D01*
G03X-1449901Y-61860I-167J-471D01*
G02X-1449934Y-62127I-1599J61D01*
G03X-1449569Y-62397I245J-51D01*
G02X-1449410Y-65279I769J-1403D01*
G03X-1450100Y-65732I-191J-462D01*
G02X-1450101Y-65745I-1600J31D01*
G03X-1449410Y-66221I500J-14D01*
G02X-1449486Y-69146I610J-1479D01*
G03X-1450200Y-69598I-214J-452D01*
G02X-1450207Y-69745I-1600J-2D01*
G03X-1449564Y-70269I498J-45D01*
G02X-1449722Y-73274I464J-1531D01*
G03X-1450413Y-73798I-194J-461D01*
G37*
G36*
G01X-1450500Y-82159D02*
G02X-1451338Y-80793I-1599J-41D01*
G03X-1450600Y-80341I238J440D01*
G02X-1450592Y-80142I1599J41D01*
G03X-1451306Y-79642I-498J49D01*
G02X-1450408Y-78358I-694J1442D01*
G03X-1449694Y-78858I498J-49D01*
G02X-1449762Y-81707I694J-1442D01*
G03X-1450500Y-82159I-238J-440D01*
G37*
G36*
G01X-445448Y-144838D02*
G02X-447341Y-147362I3519J-4611D01*
G03X-448048Y-146743I-467J180D01*
G02X-446240Y-144333I-1756J3200D01*
G03X-445448Y-144838I488J-108D01*
G37*
G36*
G01X-1315527D02*
G02X-1317420Y-147362I3519J-4611D01*
G03X-1318127Y-146743I-467J180D01*
G02X-1316318Y-144333I-1756J3200D01*
G03X-1315527Y-144838I488J-108D01*
G37*
G36*
G01X-1347998Y-169894D02*
G02X-1360173Y-158465I-8891J2729D01*
G03X-1360221Y-157514I-177J468D01*
G02X-1353556I3333J12514D01*
G03X-1353604Y-158465I129J-483D01*
G02X-1347998Y-164437I-3285J-8701D01*
G02Y-169894I-8891J-2729D01*
G37*
G36*
G01X-1223836Y-147800D02*
X-1220543D01*
X-1220366Y-147819D01*
G02X-1220752Y-152001I-223J-2088D01*
G01X-1220762Y-152000D01*
X-1223617D01*
X-1223627Y-152001D01*
G02X-1224013Y-147819I-162J2094D01*
G01X-1223836Y-147800D01*
G37*
G36*
G01X-1230265Y-136450D02*
X-1233120D01*
X-1233130Y-136451D01*
G02X-1233516Y-132269I-162J2094D01*
G01X-1233339Y-132250D01*
X-1230046D01*
X-1229869Y-132269D01*
G02X-1230255Y-136451I-223J-2088D01*
G01X-1230265Y-136450D01*
G37*
G36*
G01X-1194760Y-141597D02*
Y-143638D01*
X-1199260D01*
Y-141590D01*
G02Y-139197I2252J1197D01*
G01Y-136079D01*
G02Y-133685I2252J1197D01*
G01Y-131638D01*
X-1194760D01*
Y-133679D01*
G02Y-136085I-2248J-1203D01*
G01Y-139190D01*
G02Y-141597I-2248J-1203D01*
G37*
G36*
G01X-1258597Y-146535D02*
X-1261453D01*
X-1261463Y-146536D01*
G02X-1261849Y-142354I-162J2094D01*
G01X-1261672Y-142335D01*
X-1258379D01*
X-1258202Y-142354D01*
G02X-1258587Y-146536I-223J-2088D01*
G01X-1258597Y-146535D01*
G37*
G36*
G01X-1155390Y-146715D02*
Y-148756D01*
X-1159890D01*
Y-146709D01*
G02Y-144315I2252J1197D01*
G01Y-141197D01*
G02Y-138803I2252J1197D01*
G01Y-136756D01*
X-1155390D01*
Y-138797D01*
G02Y-141203I-2248J-1203D01*
G01Y-144309D01*
G02Y-146715I-2248J-1203D01*
G37*
G36*
G01X-1268060Y-153880D02*
X-1270916D01*
X-1270925Y-153881D01*
G02X-1271312Y-149699I-162J2094D01*
G01X-1271134Y-149680D01*
X-1267842D01*
X-1267665Y-149699D01*
G02X-1268050Y-153881I-223J-2088D01*
G01X-1268060Y-153880D01*
G37*
G36*
G01X-1194760Y-158132D02*
Y-160173D01*
X-1199260D01*
Y-158126D01*
G02Y-155732I2252J1197D01*
G01Y-152614D01*
G02Y-150221I2252J1197D01*
G01Y-148173D01*
X-1194760D01*
Y-150214D01*
G02Y-152621I-2248J-1203D01*
G01Y-155726D01*
G02Y-158132I-2248J-1203D01*
G37*
G36*
G01X-1155390Y-163250D02*
Y-165291D01*
X-1159890D01*
Y-163244D01*
G02Y-160850I2252J1197D01*
G01Y-157732D01*
G02Y-155339I2252J1197D01*
G01Y-153291D01*
X-1155390D01*
Y-155332D01*
G02Y-157739I-2248J-1203D01*
G01Y-160844D01*
G02Y-163250I-2248J-1203D01*
G37*
G36*
G01X-1206392Y-169460D02*
X-1209248D01*
X-1209257Y-169461D01*
G02X-1209643Y-165279I-162J2094D01*
G01X-1209466Y-165260D01*
X-1206173D01*
X-1205997Y-165279D01*
G02X-1206382Y-169461I-223J-2088D01*
G01X-1206392Y-169460D01*
G37*
G36*
G01X-1163264Y-174668D02*
Y-176709D01*
X-1167764D01*
Y-174661D01*
G02Y-172268I2252J1197D01*
G01Y-169150D01*
G02Y-166756I2252J1197D01*
G01Y-164709D01*
X-1163264D01*
Y-166750D01*
G02Y-169156I-2248J-1203D01*
G01Y-172261D01*
G02Y-174668I-2248J-1203D01*
G37*
G36*
G01X-1179012D02*
Y-176709D01*
X-1183512D01*
Y-174661D01*
G02Y-172268I2252J1197D01*
G01Y-169150D01*
G02Y-166756I2252J1197D01*
G01Y-164709D01*
X-1179012D01*
Y-166750D01*
G02Y-169156I-2248J-1203D01*
G01Y-172261D01*
G02Y-174668I-2248J-1203D01*
G37*
G36*
G01X-1194760D02*
Y-176709D01*
X-1199260D01*
Y-174661D01*
G02Y-172268I2252J1197D01*
G01Y-169150D01*
G02Y-166756I2252J1197D01*
G01Y-164709D01*
X-1194760D01*
Y-166750D01*
G02Y-169156I-2248J-1203D01*
G01Y-172261D01*
G02Y-174668I-2248J-1203D01*
G37*
G36*
G01X-1155390Y-179786D02*
Y-181827D01*
X-1159890D01*
Y-179779D01*
G02Y-177386I2252J1197D01*
G01Y-174268D01*
G02Y-171874I2252J1197D01*
G01Y-169827D01*
X-1155390D01*
Y-171868D01*
G02Y-174274I-2248J-1203D01*
G01Y-177379D01*
G02Y-179786I-2248J-1203D01*
G37*
G36*
G01X-1171138D02*
Y-181827D01*
X-1175638D01*
Y-179779D01*
G02Y-177386I2252J1197D01*
G01Y-174268D01*
G02Y-171874I2252J1197D01*
G01Y-169827D01*
X-1171138D01*
Y-171868D01*
G02Y-174274I-2248J-1203D01*
G01Y-177379D01*
G02Y-179786I-2248J-1203D01*
G37*
G36*
G01X-1186886D02*
Y-181827D01*
X-1191386D01*
Y-179779D01*
G02Y-177386I2252J1197D01*
G01Y-174268D01*
G02Y-171874I2252J1197D01*
G01Y-169827D01*
X-1186886D01*
Y-171868D01*
G02Y-174274I-2248J-1203D01*
G01Y-177379D01*
G02Y-179786I-2248J-1203D01*
G37*
G36*
G01X-1266485Y-185737D02*
X-1269341D01*
X-1269351Y-185738D01*
G02X-1269737Y-181556I-162J2094D01*
G01X-1269560Y-181537D01*
X-1266267D01*
X-1266090Y-181556D01*
G02X-1266475Y-185738I-223J-2088D01*
G01X-1266485Y-185737D01*
G37*
G36*
G01X-1232512Y-187480D02*
X-1235368D01*
X-1235377Y-187481D01*
G02X-1235763Y-183299I-162J2094D01*
G01X-1235586Y-183280D01*
X-1232293D01*
X-1232117Y-183299D01*
G02X-1232502Y-187481I-223J-2088D01*
G01X-1232512Y-187480D01*
G37*
G36*
G01X-1243630Y-186877D02*
Y-189733D01*
X-1243629Y-189743D01*
G02X-1247811Y-190129I-2094J-162D01*
G01X-1247830Y-189952D01*
Y-186659D01*
X-1247811Y-186482D01*
G02X-1243629Y-186868I2088J-223D01*
G01X-1243630Y-186877D01*
G37*
G36*
G01X-1164419Y-138090D02*
G02X-1166604I-1093J-2304D01*
G03Y-137186I-214J452D01*
G02X-1164419I1093J2304D01*
G03Y-138090I214J-452D01*
G37*
G36*
G01X-1188041Y-143208D02*
G02X-1190226I-1093J-2304D01*
G03Y-142304I-214J452D01*
G02Y-137696I1093J2304D01*
G03Y-136792I-214J452D01*
G02X-1188041I1093J2304D01*
G03Y-137696I214J-452D01*
G02Y-142304I-1093J-2304D01*
G03Y-143208I214J-452D01*
G37*
G36*
G01X-1164419Y-154625D02*
G02X-1166604I-1093J-2304D01*
G03Y-153721I-214J452D01*
G02X-1164419I1093J2304D01*
G03Y-154625I214J-452D01*
G37*
G36*
G01X-1180167D02*
G02X-1182352I-1093J-2304D01*
G03Y-153721I-214J452D01*
G02Y-149113I1093J2304D01*
G03Y-148210I-214J452D01*
G02Y-143601I1093J2304D01*
G03Y-142698I-214J452D01*
G02Y-138090I1093J2304D01*
G03Y-137186I-214J452D01*
G02X-1180167I1093J2304D01*
G03Y-138090I214J-452D01*
G02Y-142698I-1093J-2304D01*
G03Y-143601I214J-452D01*
G02Y-148210I-1093J-2304D01*
G03Y-149113I214J-452D01*
G02Y-153721I-1093J-2304D01*
G03Y-154625I214J-452D01*
G37*
G36*
G01X-1172293Y-159743D02*
G02X-1174478I-1093J-2304D01*
G03Y-158840I-214J452D01*
G02Y-154231I1093J2304D01*
G03Y-153328I-214J452D01*
G02Y-148720I1093J2304D01*
G03Y-147816I-214J452D01*
G02Y-143208I1093J2304D01*
G03Y-142304I-214J452D01*
G02Y-137696I1093J2304D01*
G03Y-136792I-214J452D01*
G02X-1172293I1093J2304D01*
G03Y-137696I214J-452D01*
G02Y-142304I-1093J-2304D01*
G03Y-143208I214J-452D01*
G02Y-147816I-1093J-2304D01*
G03Y-148720I214J-452D01*
G02Y-153328I-1093J-2304D01*
G03Y-154231I214J-452D01*
G02Y-158840I-1093J-2304D01*
G03Y-159743I214J-452D01*
G37*
G36*
G01X-1188041D02*
G02X-1190226I-1093J-2304D01*
G03Y-158840I-214J452D01*
G02X-1188041I1093J2304D01*
G03Y-159743I214J-452D01*
G37*
G36*
G01X-1248991Y-179958D02*
G02X-1250200Y-178368I-1600J38D01*
G03X-1249578Y-177895I122J485D01*
G02X-1246560Y-177192I1600J-38D01*
G03X-1245682Y-177208I443J231D01*
G02X-1242793Y-177438I1391J-791D01*
G03X-1242043Y-177676I468J175D01*
G02X-1239679Y-178350I901J-1322D01*
G03X-1238929Y-178553I457J203D01*
G02X-1239455Y-180498I937J-1297D01*
G03X-1240205Y-180295I-457J-203D01*
G02X-1242640Y-179559I-937J1297D01*
G03X-1243390Y-179321I-468J-175D01*
G02X-1245710Y-178739I-901J1322D01*
G03X-1246588Y-178724I-443J-231D01*
G02X-1248369Y-179485I-1391J791D01*
G03X-1248991Y-179958I-122J-485D01*
G37*
G36*
G01X-955764Y-50689D02*
X-954543Y-53160D01*
X-955375Y-55766D01*
X-956787Y-56464D01*
X-959362Y-55541D01*
X-960583Y-53070D01*
X-960286Y-52047D01*
X-956756Y-50303D01*
X-955764Y-50689D01*
G37*
G36*
G01X-961404Y-66003D02*
X-962569Y-63505D01*
X-961679Y-60919D01*
X-960251Y-60253D01*
X-957697Y-61234D01*
X-956533Y-63732D01*
X-956852Y-64748D01*
X-960420Y-66412D01*
X-961404Y-66003D01*
G37*
G36*
G01X-955764Y-65650D02*
X-954543Y-68121D01*
X-955375Y-70727D01*
X-956787Y-71424D01*
X-959362Y-70501D01*
X-960583Y-68030D01*
X-960286Y-67007D01*
X-956756Y-65263D01*
X-955764Y-65650D01*
G37*
G36*
G01Y-80610D02*
X-954543Y-83081D01*
X-955375Y-85687D01*
X-956787Y-86385D01*
X-959362Y-85462D01*
X-960583Y-82991D01*
X-960286Y-81968D01*
X-956756Y-80224D01*
X-955764Y-80610D01*
G37*
G36*
G01X-961404Y-80964D02*
X-962569Y-78466D01*
X-961679Y-75879D01*
X-960251Y-75214D01*
X-957697Y-76194D01*
X-956533Y-78692D01*
X-956852Y-79708D01*
X-960420Y-81372D01*
X-961404Y-80964D01*
G37*
G36*
G01X-955764Y-95571D02*
X-954543Y-98042D01*
X-955375Y-100648D01*
X-956787Y-101346D01*
X-959362Y-100423D01*
X-960583Y-97952D01*
X-960286Y-96928D01*
X-956756Y-95185D01*
X-955764Y-95571D01*
G37*
G36*
G01X-961404Y-95924D02*
X-962569Y-93427D01*
X-961679Y-90840D01*
X-960251Y-90174D01*
X-957697Y-91155D01*
X-956533Y-93653D01*
X-956852Y-94669D01*
X-960420Y-96333D01*
X-961404Y-95924D01*
G37*
G36*
G01X-970262Y-51043D02*
X-971427Y-48545D01*
X-970537Y-45958D01*
X-969109Y-45293D01*
X-966556Y-46273D01*
X-965391Y-48771D01*
X-965710Y-49787D01*
X-969279Y-51451D01*
X-970262Y-51043D01*
G37*
G36*
G01Y-66003D02*
X-971427Y-63505D01*
X-970537Y-60919D01*
X-969109Y-60253D01*
X-966556Y-61234D01*
X-965391Y-63732D01*
X-965710Y-64748D01*
X-969279Y-66412D01*
X-970262Y-66003D01*
G37*
G36*
G01X-964622Y-50689D02*
X-963401Y-53160D01*
X-964233Y-55766D01*
X-965645Y-56464D01*
X-968220Y-55541D01*
X-969441Y-53070D01*
X-969144Y-52047D01*
X-965615Y-50303D01*
X-964622Y-50689D01*
G37*
G36*
G01X-970262Y-80964D02*
X-971427Y-78466D01*
X-970537Y-75879D01*
X-969109Y-75214D01*
X-966556Y-76194D01*
X-965391Y-78692D01*
X-965710Y-79708D01*
X-969279Y-81372D01*
X-970262Y-80964D01*
G37*
G36*
G01X-964622Y-80610D02*
X-963401Y-83081D01*
X-964233Y-85687D01*
X-965645Y-86385D01*
X-968220Y-85462D01*
X-969441Y-82991D01*
X-969144Y-81968D01*
X-965615Y-80224D01*
X-964622Y-80610D01*
G37*
G36*
G01Y-65650D02*
X-963401Y-68121D01*
X-964233Y-70727D01*
X-965645Y-71424D01*
X-968220Y-70501D01*
X-969441Y-68030D01*
X-969144Y-67007D01*
X-965615Y-65263D01*
X-964622Y-65650D01*
G37*
G36*
G01X-970262Y-95924D02*
X-971427Y-93427D01*
X-970537Y-90840D01*
X-969109Y-90174D01*
X-966556Y-91155D01*
X-965391Y-93653D01*
X-965710Y-94669D01*
X-969279Y-96333D01*
X-970262Y-95924D01*
G37*
G36*
G01X-964622Y-95571D02*
X-963401Y-98042D01*
X-964233Y-100648D01*
X-965645Y-101346D01*
X-968220Y-100423D01*
X-969441Y-97952D01*
X-969144Y-96928D01*
X-965615Y-95185D01*
X-964622Y-95571D01*
G37*
G36*
G01X-1004711Y-66003D02*
X-1005876Y-63505D01*
X-1004986Y-60919D01*
X-1003558Y-60253D01*
X-1001004Y-61234D01*
X-999840Y-63732D01*
X-1000159Y-64748D01*
X-1003727Y-66412D01*
X-1004711Y-66003D01*
G37*
G36*
G01X-999071Y-50689D02*
X-997850Y-53160D01*
X-998682Y-55766D01*
X-1000094Y-56464D01*
X-1002669Y-55541D01*
X-1003890Y-53070D01*
X-1003593Y-52047D01*
X-1000064Y-50303D01*
X-999071Y-50689D01*
G37*
G36*
G01X-1004711Y-80964D02*
X-1005876Y-78466D01*
X-1004986Y-75879D01*
X-1003558Y-75214D01*
X-1001004Y-76194D01*
X-999840Y-78692D01*
X-1000159Y-79708D01*
X-1003727Y-81372D01*
X-1004711Y-80964D01*
G37*
G36*
G01X-999071Y-80610D02*
X-997850Y-83081D01*
X-998682Y-85687D01*
X-1000094Y-86385D01*
X-1002669Y-85462D01*
X-1003890Y-82991D01*
X-1003593Y-81968D01*
X-1000064Y-80224D01*
X-999071Y-80610D01*
G37*
G36*
G01Y-65650D02*
X-997850Y-68121D01*
X-998682Y-70727D01*
X-1000094Y-71424D01*
X-1002669Y-70501D01*
X-1003890Y-68030D01*
X-1003593Y-67007D01*
X-1000064Y-65263D01*
X-999071Y-65650D01*
G37*
G36*
G01X-1004711Y-95924D02*
X-1005876Y-93427D01*
X-1004986Y-90840D01*
X-1003558Y-90174D01*
X-1001004Y-91155D01*
X-999840Y-93653D01*
X-1000159Y-94669D01*
X-1003727Y-96333D01*
X-1004711Y-95924D01*
G37*
G36*
G01X-999071Y-95571D02*
X-997850Y-98042D01*
X-998682Y-100648D01*
X-1000094Y-101346D01*
X-1002669Y-100423D01*
X-1003890Y-97952D01*
X-1003593Y-96928D01*
X-1000064Y-95185D01*
X-999071Y-95571D01*
G37*
G36*
G01X-1013569Y-51043D02*
X-1014734Y-48545D01*
X-1013844Y-45958D01*
X-1012416Y-45293D01*
X-1009863Y-46273D01*
X-1008698Y-48771D01*
X-1009017Y-49787D01*
X-1012586Y-51451D01*
X-1013569Y-51043D01*
G37*
G36*
G01Y-66003D02*
X-1014734Y-63505D01*
X-1013844Y-60919D01*
X-1012416Y-60253D01*
X-1009863Y-61234D01*
X-1008698Y-63732D01*
X-1009017Y-64748D01*
X-1012586Y-66412D01*
X-1013569Y-66003D01*
G37*
G36*
G01X-1007929Y-50689D02*
X-1006708Y-53160D01*
X-1007540Y-55766D01*
X-1008952Y-56464D01*
X-1011527Y-55541D01*
X-1012748Y-53070D01*
X-1012452Y-52047D01*
X-1008922Y-50303D01*
X-1007929Y-50689D01*
G37*
G36*
G01Y-65650D02*
X-1006708Y-68121D01*
X-1007540Y-70727D01*
X-1008952Y-71424D01*
X-1011527Y-70501D01*
X-1012748Y-68030D01*
X-1012452Y-67007D01*
X-1008922Y-65263D01*
X-1007929Y-65650D01*
G37*
G36*
G01Y-80610D02*
X-1006708Y-83081D01*
X-1007540Y-85687D01*
X-1008952Y-86385D01*
X-1011527Y-85462D01*
X-1012748Y-82991D01*
X-1012452Y-81968D01*
X-1008922Y-80224D01*
X-1007929Y-80610D01*
G37*
G36*
G01X-1013569Y-80964D02*
X-1014734Y-78466D01*
X-1013844Y-75879D01*
X-1012416Y-75214D01*
X-1009863Y-76194D01*
X-1008698Y-78692D01*
X-1009017Y-79708D01*
X-1012586Y-81372D01*
X-1013569Y-80964D01*
G37*
G36*
G01X-1007929Y-95571D02*
X-1006708Y-98042D01*
X-1007540Y-100648D01*
X-1008952Y-101346D01*
X-1011527Y-100423D01*
X-1012748Y-97952D01*
X-1012452Y-96928D01*
X-1008922Y-95185D01*
X-1007929Y-95571D01*
G37*
G36*
G01X-1013569Y-95924D02*
X-1014734Y-93427D01*
X-1013844Y-90840D01*
X-1012416Y-90174D01*
X-1009863Y-91155D01*
X-1008698Y-93653D01*
X-1009017Y-94669D01*
X-1012586Y-96333D01*
X-1013569Y-95924D01*
G37*
G36*
G01X-980742Y-141594D02*
Y-143638D01*
X-985242D01*
Y-141594D01*
G02Y-139194I2250J1200D01*
G01Y-136082D01*
G02Y-133682I2250J1200D01*
G01Y-131638D01*
X-980742D01*
Y-133682D01*
G02Y-136082I-2250J-1200D01*
G01Y-139194D01*
G02Y-141594I-2250J-1200D01*
G37*
G36*
G01X-996490D02*
Y-143638D01*
X-1000990D01*
Y-141594D01*
G02Y-139194I2250J1200D01*
G01Y-136082D01*
G02Y-133682I2250J1200D01*
G01Y-131638D01*
X-996490D01*
Y-133682D01*
G02Y-136082I-2250J-1200D01*
G01Y-139194D01*
G02Y-141594I-2250J-1200D01*
G37*
G36*
G01X-1012238D02*
Y-143638D01*
X-1016738D01*
Y-141594D01*
G02Y-139194I2250J1200D01*
G01Y-136082D01*
G02Y-133682I2250J1200D01*
G01Y-131638D01*
X-1012238D01*
Y-133682D01*
G02Y-136082I-2250J-1200D01*
G01Y-139194D01*
G02Y-141594I-2250J-1200D01*
G37*
G36*
G01X-972868Y-146712D02*
Y-148756D01*
X-977368D01*
Y-146712D01*
G02Y-144312I2250J1200D01*
G01Y-141200D01*
G02Y-138800I2250J1200D01*
G01Y-136756D01*
X-972868D01*
Y-138800D01*
G02Y-141200I-2250J-1200D01*
G01Y-144312D01*
G02Y-146712I-2250J-1200D01*
G37*
G36*
G01X-988616D02*
Y-148756D01*
X-993116D01*
Y-146712D01*
G02Y-144312I2250J1200D01*
G01Y-141200D01*
G02Y-138800I2250J1200D01*
G01Y-136756D01*
X-988616D01*
Y-138800D01*
G02Y-141200I-2250J-1200D01*
G01Y-144312D01*
G02Y-146712I-2250J-1200D01*
G37*
G36*
G01X-1004364D02*
Y-148756D01*
X-1008864D01*
Y-146712D01*
G02Y-144312I2250J1200D01*
G01Y-141200D01*
G02Y-138800I2250J1200D01*
G01Y-136756D01*
X-1004364D01*
Y-138800D01*
G02Y-141200I-2250J-1200D01*
G01Y-144312D01*
G02Y-146712I-2250J-1200D01*
G37*
G36*
G01X-980742Y-158129D02*
Y-160173D01*
X-985242D01*
Y-158129D01*
G02Y-155729I2250J1200D01*
G01Y-152617D01*
G02Y-150217I2250J1200D01*
G01Y-148173D01*
X-980742D01*
Y-150217D01*
G02Y-152617I-2250J-1200D01*
G01Y-155729D01*
G02Y-158129I-2250J-1200D01*
G37*
G36*
G01X-996490D02*
Y-160173D01*
X-1000990D01*
Y-158129D01*
G02Y-155729I2250J1200D01*
G01Y-152617D01*
G02Y-150217I2250J1200D01*
G01Y-148173D01*
X-996490D01*
Y-150217D01*
G02Y-152617I-2250J-1200D01*
G01Y-155729D01*
G02Y-158129I-2250J-1200D01*
G37*
G36*
G01X-1012238D02*
Y-160173D01*
X-1016738D01*
Y-158129D01*
G02Y-155729I2250J1200D01*
G01Y-152617D01*
G02Y-150217I2250J1200D01*
G01Y-148173D01*
X-1012238D01*
Y-150217D01*
G02Y-152617I-2250J-1200D01*
G01Y-155729D01*
G02Y-158129I-2250J-1200D01*
G37*
G36*
G01X-972868Y-163247D02*
Y-165291D01*
X-977368D01*
Y-163247D01*
G02Y-160847I2250J1200D01*
G01Y-157735D01*
G02Y-155335I2250J1200D01*
G01Y-153291D01*
X-972868D01*
Y-155335D01*
G02Y-157735I-2250J-1200D01*
G01Y-160847D01*
G02Y-163247I-2250J-1200D01*
G37*
G36*
G01X-988616D02*
Y-165291D01*
X-993116D01*
Y-163247D01*
G02Y-160847I2250J1200D01*
G01Y-157735D01*
G02Y-155335I2250J1200D01*
G01Y-153291D01*
X-988616D01*
Y-155335D01*
G02Y-157735I-2250J-1200D01*
G01Y-160847D01*
G02Y-163247I-2250J-1200D01*
G37*
G36*
G01X-1004364D02*
Y-165291D01*
X-1008864D01*
Y-163247D01*
G02Y-160847I2250J1200D01*
G01Y-157735D01*
G02Y-155335I2250J1200D01*
G01Y-153291D01*
X-1004364D01*
Y-155335D01*
G02Y-157735I-2250J-1200D01*
G01Y-160847D01*
G02Y-163247I-2250J-1200D01*
G37*
G36*
G01X-980742Y-174665D02*
Y-176709D01*
X-985242D01*
Y-174665D01*
G02Y-172265I2250J1200D01*
G01Y-169153D01*
G02Y-166753I2250J1200D01*
G01Y-164709D01*
X-980742D01*
Y-166753D01*
G02Y-169153I-2250J-1200D01*
G01Y-172265D01*
G02Y-174665I-2250J-1200D01*
G37*
G36*
G01X-1012238D02*
Y-176709D01*
X-1016738D01*
Y-174665D01*
G02Y-172265I2250J1200D01*
G01Y-169153D01*
G02Y-166753I2250J1200D01*
G01Y-164709D01*
X-1012238D01*
Y-166753D01*
G02Y-169153I-2250J-1200D01*
G01Y-172265D01*
G02Y-174665I-2250J-1200D01*
G37*
G36*
G01X-972868Y-179783D02*
Y-181827D01*
X-977368D01*
Y-179783D01*
G02Y-177383I2250J1200D01*
G01Y-174271D01*
G02Y-171871I2250J1200D01*
G01Y-169827D01*
X-972868D01*
Y-171871D01*
G02Y-174271I-2250J-1200D01*
G01Y-177383D01*
G02Y-179783I-2250J-1200D01*
G37*
G36*
G01X-1004364D02*
Y-181827D01*
X-1008864D01*
Y-179783D01*
G02Y-177383I2250J1200D01*
G01Y-174271D01*
G02Y-171871I2250J1200D01*
G01Y-169827D01*
X-1004364D01*
Y-171871D01*
G02Y-174271I-2250J-1200D01*
G01Y-177383D01*
G02Y-179783I-2250J-1200D01*
G37*
G36*
G01X-997648Y-171160D02*
G02X-999833I-1093J-2304D01*
G03Y-170257I-214J452D01*
G02X-997648I1093J2304D01*
G03Y-171160I214J-452D01*
G37*
G36*
G01X-989774Y-176279D02*
G02X-991959I-1093J-2304D01*
G03Y-175375I-214J452D01*
G02X-989774I1093J2304D01*
G03Y-176279I214J-452D01*
G37*
G36*
G01X-590011Y-81803D02*
Y-86977D01*
X-590029Y-87106D01*
G02X-593212Y-86800I-1585J216D01*
G01X-593211Y-86793D01*
Y-81986D01*
X-593212Y-81979D01*
G02X-590029Y-81674I1598J90D01*
G01X-590011Y-81803D01*
G37*
G36*
G01X-600011D02*
Y-86977D01*
X-600029Y-87106D01*
G02X-603212Y-86800I-1585J216D01*
G01X-603211Y-86793D01*
Y-81986D01*
X-603212Y-81979D01*
G02X-600029Y-81674I1598J90D01*
G01X-600011Y-81803D01*
G37*
G36*
G01X-610011D02*
Y-86977D01*
X-610029Y-87106D01*
G02X-613212Y-86800I-1585J216D01*
G01X-613211Y-86793D01*
Y-81986D01*
X-613212Y-81979D01*
G02X-610029Y-81674I1598J90D01*
G01X-610011Y-81803D01*
G37*
G36*
G01X-595011Y-91803D02*
Y-96977D01*
X-595029Y-97106D01*
G02X-598212Y-96800I-1585J216D01*
G01X-598211Y-96793D01*
Y-91986D01*
X-598212Y-91979D01*
G02X-595029Y-91674I1598J90D01*
G01X-595011Y-91803D01*
G37*
G36*
G01X-605011D02*
Y-96977D01*
X-605029Y-97106D01*
G02X-608212Y-96800I-1585J216D01*
G01X-608211Y-96793D01*
Y-91986D01*
X-608212Y-91979D01*
G02X-605029Y-91674I1598J90D01*
G01X-605011Y-91803D01*
G37*
G36*
G01X-615011D02*
Y-96977D01*
X-615029Y-97106D01*
G02X-618212Y-96800I-1585J216D01*
G01X-618211Y-96793D01*
Y-91986D01*
X-618212Y-91979D01*
G02X-615029Y-91674I1598J90D01*
G01X-615011Y-91803D01*
G37*
G36*
G01X-590011Y-101803D02*
Y-106977D01*
X-590029Y-107106D01*
G02X-593212Y-106800I-1585J216D01*
G01X-593211Y-106793D01*
Y-101986D01*
X-593212Y-101979D01*
G02X-590029Y-101674I1598J90D01*
G01X-590011Y-101803D01*
G37*
G36*
G01X-600011D02*
Y-106977D01*
X-600029Y-107106D01*
G02X-603212Y-106800I-1585J216D01*
G01X-603211Y-106793D01*
Y-101986D01*
X-603212Y-101979D01*
G02X-600029Y-101674I1598J90D01*
G01X-600011Y-101803D01*
G37*
G36*
G01X-610011D02*
Y-106977D01*
X-610029Y-107106D01*
G02X-613212Y-106800I-1585J216D01*
G01X-613211Y-106793D01*
Y-101986D01*
X-613212Y-101979D01*
G02X-610029Y-101674I1598J90D01*
G01X-610011Y-101803D01*
G37*
G36*
G01X-680665Y-108132D02*
Y-110173D01*
X-685165D01*
Y-108126D01*
G02Y-105732I2252J1197D01*
G01Y-102614D01*
G02Y-100221I2252J1197D01*
G01Y-98173D01*
X-680665D01*
Y-100214D01*
G02Y-102621I-2248J-1203D01*
G01Y-105726D01*
G02Y-108132I-2248J-1203D01*
G37*
G36*
G01X-696413D02*
Y-110173D01*
X-700913D01*
Y-108126D01*
G02Y-105732I2252J1197D01*
G01Y-102614D01*
G02Y-100221I2252J1197D01*
G01Y-98173D01*
X-696413D01*
Y-100214D01*
G02Y-102621I-2248J-1203D01*
G01Y-105726D01*
G02Y-108132I-2248J-1203D01*
G37*
G36*
G01X-712161D02*
Y-110173D01*
X-716661D01*
Y-108126D01*
G02Y-105732I2252J1197D01*
G01Y-102614D01*
G02Y-100221I2252J1197D01*
G01Y-98173D01*
X-712161D01*
Y-100214D01*
G02Y-102621I-2248J-1203D01*
G01Y-105726D01*
G02Y-108132I-2248J-1203D01*
G37*
G36*
G01X-727909D02*
Y-110173D01*
X-732409D01*
Y-108126D01*
G02Y-105732I2252J1197D01*
G01Y-102614D01*
G02Y-100221I2252J1197D01*
G01Y-98173D01*
X-727909D01*
Y-100214D01*
G02Y-102621I-2248J-1203D01*
G01Y-105726D01*
G02Y-108132I-2248J-1203D01*
G37*
G36*
G01X-672791Y-113250D02*
Y-115291D01*
X-677291D01*
Y-113244D01*
G02Y-110850I2252J1197D01*
G01Y-107732D01*
G02Y-105339I2252J1197D01*
G01Y-103291D01*
X-672791D01*
Y-105332D01*
G02Y-107739I-2248J-1203D01*
G01Y-110844D01*
G02Y-113250I-2248J-1203D01*
G37*
G36*
G01X-688539D02*
Y-115291D01*
X-693039D01*
Y-113244D01*
G02Y-110850I2252J1197D01*
G01Y-107732D01*
G02Y-105339I2252J1197D01*
G01Y-103291D01*
X-688539D01*
Y-105332D01*
G02Y-107739I-2248J-1203D01*
G01Y-110844D01*
G02Y-113250I-2248J-1203D01*
G37*
G36*
G01X-704287D02*
Y-115291D01*
X-708787D01*
Y-113244D01*
G02Y-110850I2252J1197D01*
G01Y-107732D01*
G02Y-105339I2252J1197D01*
G01Y-103291D01*
X-704287D01*
Y-105332D01*
G02Y-107739I-2248J-1203D01*
G01Y-110844D01*
G02Y-113250I-2248J-1203D01*
G37*
G36*
G01X-720035D02*
Y-115291D01*
X-724535D01*
Y-113244D01*
G02Y-110850I2252J1197D01*
G01Y-107732D01*
G02Y-105339I2252J1197D01*
G01Y-103291D01*
X-720035D01*
Y-105332D01*
G02Y-107739I-2248J-1203D01*
G01Y-110844D01*
G02Y-113250I-2248J-1203D01*
G37*
G36*
G01X-595011Y-111803D02*
Y-116977D01*
X-595029Y-117106D01*
G02X-598212Y-116800I-1585J216D01*
G01X-598211Y-116793D01*
Y-111986D01*
X-598212Y-111979D01*
G02X-595029Y-111674I1598J90D01*
G01X-595011Y-111803D01*
G37*
G36*
G01X-605011D02*
Y-116977D01*
X-605029Y-117106D01*
G02X-608212Y-116800I-1585J216D01*
G01X-608211Y-116793D01*
Y-111986D01*
X-608212Y-111979D01*
G02X-605029Y-111674I1598J90D01*
G01X-605011Y-111803D01*
G37*
G36*
G01X-615011D02*
Y-116977D01*
X-615029Y-117106D01*
G02X-618212Y-116800I-1585J216D01*
G01X-618211Y-116793D01*
Y-111986D01*
X-618212Y-111979D01*
G02X-615029Y-111674I1598J90D01*
G01X-615011Y-111803D01*
G37*
G36*
G01X-680665Y-124668D02*
Y-126709D01*
X-685165D01*
Y-124661D01*
G02Y-122268I2252J1197D01*
G01Y-119150D01*
G02Y-116756I2252J1197D01*
G01Y-114709D01*
X-680665D01*
Y-116750D01*
G02Y-119156I-2248J-1203D01*
G01Y-122261D01*
G02Y-124668I-2248J-1203D01*
G37*
G36*
G01X-696413D02*
Y-126709D01*
X-700913D01*
Y-124661D01*
G02Y-122268I2252J1197D01*
G01Y-119150D01*
G02Y-116756I2252J1197D01*
G01Y-114709D01*
X-696413D01*
Y-116750D01*
G02Y-119156I-2248J-1203D01*
G01Y-122261D01*
G02Y-124668I-2248J-1203D01*
G37*
G36*
G01X-712161D02*
Y-126709D01*
X-716661D01*
Y-124661D01*
G02Y-122268I2252J1197D01*
G01Y-119150D01*
G02Y-116756I2252J1197D01*
G01Y-114709D01*
X-712161D01*
Y-116750D01*
G02Y-119156I-2248J-1203D01*
G01Y-122261D01*
G02Y-124668I-2248J-1203D01*
G37*
G36*
G01X-727909D02*
Y-126709D01*
X-732409D01*
Y-124661D01*
G02Y-122268I2252J1197D01*
G01Y-119150D01*
G02Y-116756I2252J1197D01*
G01Y-114709D01*
X-727909D01*
Y-116750D01*
G02Y-119156I-2248J-1203D01*
G01Y-122261D01*
G02Y-124668I-2248J-1203D01*
G37*
G36*
G01X-590011Y-121803D02*
Y-126977D01*
X-590029Y-127106D01*
G02X-593212Y-126800I-1585J216D01*
G01X-593211Y-126793D01*
Y-121986D01*
X-593212Y-121979D01*
G02X-590029Y-121674I1598J90D01*
G01X-590011Y-121803D01*
G37*
G36*
G01X-600011D02*
Y-126977D01*
X-600029Y-127106D01*
G02X-603212Y-126800I-1585J216D01*
G01X-603211Y-126793D01*
Y-121986D01*
X-603212Y-121979D01*
G02X-600029Y-121674I1598J90D01*
G01X-600011Y-121803D01*
G37*
G36*
G01X-610011D02*
Y-126977D01*
X-610029Y-127106D01*
G02X-613212Y-126800I-1585J216D01*
G01X-613211Y-126793D01*
Y-121986D01*
X-613212Y-121979D01*
G02X-610029Y-121674I1598J90D01*
G01X-610011Y-121803D01*
G37*
G36*
G01X-672791Y-129786D02*
Y-131827D01*
X-677291D01*
Y-129779D01*
G02Y-127386I2252J1197D01*
G01Y-124268D01*
G02Y-121874I2252J1197D01*
G01Y-119827D01*
X-672791D01*
Y-121868D01*
G02Y-124274I-2248J-1203D01*
G01Y-127379D01*
G02Y-129786I-2248J-1203D01*
G37*
G36*
G01X-688539D02*
Y-131827D01*
X-693039D01*
Y-129779D01*
G02Y-127386I2252J1197D01*
G01Y-124268D01*
G02Y-121874I2252J1197D01*
G01Y-119827D01*
X-688539D01*
Y-121868D01*
G02Y-124274I-2248J-1203D01*
G01Y-127379D01*
G02Y-129786I-2248J-1203D01*
G37*
G36*
G01X-704287D02*
Y-131827D01*
X-708787D01*
Y-129779D01*
G02Y-127386I2252J1197D01*
G01Y-124268D01*
G02Y-121874I2252J1197D01*
G01Y-119827D01*
X-704287D01*
Y-121868D01*
G02Y-124274I-2248J-1203D01*
G01Y-127379D01*
G02Y-129786I-2248J-1203D01*
G37*
G36*
G01X-720035D02*
Y-131827D01*
X-724535D01*
Y-129779D01*
G02Y-127386I2252J1197D01*
G01Y-124268D01*
G02Y-121874I2252J1197D01*
G01Y-119827D01*
X-720035D01*
Y-121868D01*
G02Y-124274I-2248J-1203D01*
G01Y-127379D01*
G02Y-129786I-2248J-1203D01*
G37*
G36*
G01X-735783D02*
Y-131827D01*
X-740283D01*
Y-129779D01*
G02Y-127386I2252J1197D01*
G01Y-124268D01*
G02Y-121874I2252J1197D01*
G01Y-119827D01*
X-735783D01*
Y-121868D01*
G02Y-124274I-2248J-1203D01*
G01Y-127379D01*
G02Y-129786I-2248J-1203D01*
G37*
G36*
G01X-595011Y-131803D02*
Y-136977D01*
X-595029Y-137106D01*
G02X-598212Y-136800I-1585J216D01*
G01X-598211Y-136793D01*
Y-131986D01*
X-598212Y-131979D01*
G02X-595029Y-131674I1598J90D01*
G01X-595011Y-131803D01*
G37*
G36*
G01X-605011D02*
Y-136977D01*
X-605029Y-137106D01*
G02X-608212Y-136800I-1585J216D01*
G01X-608211Y-136793D01*
Y-131986D01*
X-608212Y-131979D01*
G02X-605029Y-131674I1598J90D01*
G01X-605011Y-131803D01*
G37*
G36*
G01X-615011D02*
Y-136977D01*
X-615029Y-137106D01*
G02X-618212Y-136800I-1585J216D01*
G01X-618211Y-136793D01*
Y-131986D01*
X-618212Y-131979D01*
G02X-615029Y-131674I1598J90D01*
G01X-615011Y-131803D01*
G37*
G36*
G01X-680665Y-141203D02*
Y-143244D01*
X-685165D01*
Y-141197D01*
G02Y-138803I2252J1197D01*
G01Y-135685D01*
G02Y-133291I2252J1197D01*
G01Y-131244D01*
X-680665D01*
Y-133285D01*
G02Y-135691I-2248J-1203D01*
G01Y-138797D01*
G02Y-141203I-2248J-1203D01*
G37*
G36*
G01X-696413D02*
Y-143244D01*
X-700913D01*
Y-141197D01*
G02Y-138803I2252J1197D01*
G01Y-135685D01*
G02Y-133291I2252J1197D01*
G01Y-131244D01*
X-696413D01*
Y-133285D01*
G02Y-135691I-2248J-1203D01*
G01Y-138797D01*
G02Y-141203I-2248J-1203D01*
G37*
G36*
G01X-712161D02*
Y-143244D01*
X-716661D01*
Y-141197D01*
G02Y-138803I2252J1197D01*
G01Y-135685D01*
G02Y-133291I2252J1197D01*
G01Y-131244D01*
X-712161D01*
Y-133285D01*
G02Y-135691I-2248J-1203D01*
G01Y-138797D01*
G02Y-141203I-2248J-1203D01*
G37*
G36*
G01X-727909D02*
Y-143244D01*
X-732409D01*
Y-141197D01*
G02Y-138803I2252J1197D01*
G01Y-135685D01*
G02Y-133291I2252J1197D01*
G01Y-131244D01*
X-727909D01*
Y-133285D01*
G02Y-135691I-2248J-1203D01*
G01Y-138797D01*
G02Y-141203I-2248J-1203D01*
G37*
G36*
G01X-672791Y-146321D02*
Y-148362D01*
X-677291D01*
Y-146315D01*
G02Y-143921I2252J1197D01*
G01Y-140803D01*
G02Y-138410I2252J1197D01*
G01Y-136362D01*
X-672791D01*
Y-138403D01*
G02Y-140810I-2248J-1203D01*
G01Y-143915D01*
G02Y-146321I-2248J-1203D01*
G37*
G36*
G01X-688539D02*
Y-148362D01*
X-693039D01*
Y-146315D01*
G02Y-143921I2252J1197D01*
G01Y-140803D01*
G02Y-138410I2252J1197D01*
G01Y-136362D01*
X-688539D01*
Y-138403D01*
G02Y-140810I-2248J-1203D01*
G01Y-143915D01*
G02Y-146321I-2248J-1203D01*
G37*
G36*
G01X-704287D02*
Y-148362D01*
X-708787D01*
Y-146315D01*
G02Y-143921I2252J1197D01*
G01Y-140803D01*
G02Y-138410I2252J1197D01*
G01Y-136362D01*
X-704287D01*
Y-138403D01*
G02Y-140810I-2248J-1203D01*
G01Y-143915D01*
G02Y-146321I-2248J-1203D01*
G37*
G36*
G01X-720035D02*
Y-148362D01*
X-724535D01*
Y-146315D01*
G02Y-143921I2252J1197D01*
G01Y-140803D01*
G02Y-138410I2252J1197D01*
G01Y-136362D01*
X-720035D01*
Y-138403D01*
G02Y-140810I-2248J-1203D01*
G01Y-143915D01*
G02Y-146321I-2248J-1203D01*
G37*
G36*
G01X-735783D02*
Y-148362D01*
X-740283D01*
Y-146315D01*
G02Y-143921I2252J1197D01*
G01Y-140803D01*
G02Y-138410I2252J1197D01*
G01Y-136362D01*
X-735783D01*
Y-138403D01*
G02Y-140810I-2248J-1203D01*
G01Y-143915D01*
G02Y-146321I-2248J-1203D01*
G37*
G36*
G01X-590011Y-141803D02*
Y-146977D01*
X-590029Y-147106D01*
G02X-593212Y-146800I-1585J216D01*
G01X-593211Y-146793D01*
Y-141986D01*
X-593212Y-141979D01*
G02X-590029Y-141674I1598J90D01*
G01X-590011Y-141803D01*
G37*
G36*
G01X-600011D02*
Y-146977D01*
X-600029Y-147106D01*
G02X-603212Y-146800I-1585J216D01*
G01X-603211Y-146793D01*
Y-141986D01*
X-603212Y-141979D01*
G02X-600029Y-141674I1598J90D01*
G01X-600011Y-141803D01*
G37*
G36*
G01X-610011D02*
Y-146977D01*
X-610029Y-147106D01*
G02X-613212Y-146800I-1585J216D01*
G01X-613211Y-146793D01*
Y-141986D01*
X-613212Y-141979D01*
G02X-610029Y-141674I1598J90D01*
G01X-610011Y-141803D01*
G37*
G36*
G01X-595011Y-151803D02*
Y-156977D01*
X-595029Y-157106D01*
G02X-598212Y-156800I-1585J216D01*
G01X-598211Y-156793D01*
Y-151986D01*
X-598212Y-151979D01*
G02X-595029Y-151674I1598J90D01*
G01X-595011Y-151803D01*
G37*
G36*
G01X-605011D02*
Y-156977D01*
X-605029Y-157106D01*
G02X-608212Y-156800I-1585J216D01*
G01X-608211Y-156793D01*
Y-151986D01*
X-608212Y-151979D01*
G02X-605029Y-151674I1598J90D01*
G01X-605011Y-151803D01*
G37*
G36*
G01X-615011D02*
Y-156977D01*
X-615029Y-157106D01*
G02X-618212Y-156800I-1585J216D01*
G01X-618211Y-156793D01*
Y-151986D01*
X-618212Y-151979D01*
G02X-615029Y-151674I1598J90D01*
G01X-615011Y-151803D01*
G37*
G36*
G01X-680665Y-157739D02*
Y-159780D01*
X-685165D01*
Y-157732D01*
G02Y-155339I2252J1197D01*
G01Y-152220D01*
G02Y-149827I2252J1197D01*
G01Y-147780D01*
X-680665D01*
Y-149820D01*
G02Y-152227I-2248J-1203D01*
G01Y-155332D01*
G02Y-157739I-2248J-1203D01*
G37*
G36*
G01X-696413D02*
Y-159780D01*
X-700913D01*
Y-157732D01*
G02Y-155339I2252J1197D01*
G01Y-152220D01*
G02Y-149827I2252J1197D01*
G01Y-147780D01*
X-696413D01*
Y-149820D01*
G02Y-152227I-2248J-1203D01*
G01Y-155332D01*
G02Y-157739I-2248J-1203D01*
G37*
G36*
G01X-712161D02*
Y-159780D01*
X-716661D01*
Y-157732D01*
G02Y-155339I2252J1197D01*
G01Y-152220D01*
G02Y-149827I2252J1197D01*
G01Y-147780D01*
X-712161D01*
Y-149820D01*
G02Y-152227I-2248J-1203D01*
G01Y-155332D01*
G02Y-157739I-2248J-1203D01*
G37*
G36*
G01X-727909D02*
Y-159780D01*
X-732409D01*
Y-157732D01*
G02Y-155339I2252J1197D01*
G01Y-152220D01*
G02Y-149827I2252J1197D01*
G01Y-147780D01*
X-727909D01*
Y-149820D01*
G02Y-152227I-2248J-1203D01*
G01Y-155332D01*
G02Y-157739I-2248J-1203D01*
G37*
G36*
G01X-672791Y-162857D02*
Y-164898D01*
X-677291D01*
Y-162850D01*
G02Y-160457I2252J1197D01*
G01Y-157339D01*
G02Y-154945I2252J1197D01*
G01Y-152898D01*
X-672791D01*
Y-154939D01*
G02Y-157345I-2248J-1203D01*
G01Y-160450D01*
G02Y-162857I-2248J-1203D01*
G37*
G36*
G01X-688539D02*
Y-164898D01*
X-693039D01*
Y-162850D01*
G02Y-160457I2252J1197D01*
G01Y-157339D01*
G02Y-154945I2252J1197D01*
G01Y-152898D01*
X-688539D01*
Y-154939D01*
G02Y-157345I-2248J-1203D01*
G01Y-160450D01*
G02Y-162857I-2248J-1203D01*
G37*
G36*
G01X-704287D02*
Y-164898D01*
X-708787D01*
Y-162850D01*
G02Y-160457I2252J1197D01*
G01Y-157339D01*
G02Y-154945I2252J1197D01*
G01Y-152898D01*
X-704287D01*
Y-154939D01*
G02Y-157345I-2248J-1203D01*
G01Y-160450D01*
G02Y-162857I-2248J-1203D01*
G37*
G36*
G01X-720035D02*
Y-164898D01*
X-724535D01*
Y-162850D01*
G02Y-160457I2252J1197D01*
G01Y-157339D01*
G02Y-154945I2252J1197D01*
G01Y-152898D01*
X-720035D01*
Y-154939D01*
G02Y-157345I-2248J-1203D01*
G01Y-160450D01*
G02Y-162857I-2248J-1203D01*
G37*
G36*
G01X-735783D02*
Y-164898D01*
X-740283D01*
Y-162850D01*
G02Y-160457I2252J1197D01*
G01Y-157339D01*
G02Y-154945I2252J1197D01*
G01Y-152898D01*
X-735783D01*
Y-154939D01*
G02Y-157345I-2248J-1203D01*
G01Y-160450D01*
G02Y-162857I-2248J-1203D01*
G37*
G36*
G01X-590011Y-161803D02*
Y-166977D01*
X-590029Y-167106D01*
G02X-593212Y-166800I-1585J216D01*
G01X-593211Y-166793D01*
Y-161986D01*
X-593212Y-161979D01*
G02X-590029Y-161674I1598J90D01*
G01X-590011Y-161803D01*
G37*
G36*
G01X-600011D02*
Y-166977D01*
X-600029Y-167106D01*
G02X-603212Y-166800I-1585J216D01*
G01X-603211Y-166793D01*
Y-161986D01*
X-603212Y-161979D01*
G02X-600029Y-161674I1598J90D01*
G01X-600011Y-161803D01*
G37*
G36*
G01X-610011D02*
Y-166977D01*
X-610029Y-167106D01*
G02X-613212Y-166800I-1585J216D01*
G01X-613211Y-166793D01*
Y-161986D01*
X-613212Y-161979D01*
G02X-610029Y-161674I1598J90D01*
G01X-610011Y-161803D01*
G37*
G36*
G01X-680665Y-174274D02*
Y-176315D01*
X-685165D01*
Y-174268D01*
G02Y-171874I2252J1197D01*
G01Y-168756D01*
G02Y-166362I2252J1197D01*
G01Y-164315D01*
X-680665D01*
Y-166356D01*
G02Y-168762I-2248J-1203D01*
G01Y-171868D01*
G02Y-174274I-2248J-1203D01*
G37*
G36*
G01X-696413D02*
Y-176315D01*
X-700913D01*
Y-174268D01*
G02Y-171874I2252J1197D01*
G01Y-168756D01*
G02Y-166362I2252J1197D01*
G01Y-164315D01*
X-696413D01*
Y-166356D01*
G02Y-168762I-2248J-1203D01*
G01Y-171868D01*
G02Y-174274I-2248J-1203D01*
G37*
G36*
G01X-712161D02*
Y-176315D01*
X-716661D01*
Y-174268D01*
G02Y-171874I2252J1197D01*
G01Y-168756D01*
G02Y-166362I2252J1197D01*
G01Y-164315D01*
X-712161D01*
Y-166356D01*
G02Y-168762I-2248J-1203D01*
G01Y-171868D01*
G02Y-174274I-2248J-1203D01*
G37*
G36*
G01X-727909D02*
Y-176315D01*
X-732409D01*
Y-174268D01*
G02Y-171874I2252J1197D01*
G01Y-168756D01*
G02Y-166362I2252J1197D01*
G01Y-164315D01*
X-727909D01*
Y-166356D01*
G02Y-168762I-2248J-1203D01*
G01Y-171868D01*
G02Y-174274I-2248J-1203D01*
G37*
G36*
G01X-353757Y-147800D02*
X-350465D01*
X-350288Y-147819D01*
G02X-350673Y-152001I-223J-2088D01*
G01X-350683Y-152000D01*
X-353539D01*
X-353548Y-152001D01*
G02X-353935Y-147819I-162J2094D01*
G01X-353757Y-147800D01*
G37*
G36*
G01X-378147Y-180281D02*
G02X-379660Y-179506I-1375J-819D01*
G03X-379274Y-178752I-43J498D01*
G02X-376482Y-177192I1375J819D01*
G03X-375604Y-177208I443J231D01*
G02X-372714Y-177438I1391J-791D01*
G03X-371964Y-177676I468J175D01*
G02X-369600Y-178350I901J-1322D01*
G03X-368850Y-178553I457J203D01*
G02X-369376Y-180498I937J-1297D01*
G03X-370126Y-180295I-457J-203D01*
G02X-372562Y-179559I-937J1297D01*
G03X-373312Y-179321I-468J-175D01*
G02X-375631Y-178739I-901J1322D01*
G03X-376509Y-178724I-443J-231D01*
G02X-377761Y-179527I-1391J791D01*
G03X-378147Y-180281I43J-498D01*
G37*
G36*
G01X-91156Y-44741D02*
G02X-83889Y-30498I1195J8365D01*
G02X-84008Y-42373I-6071J-5877D01*
G02X-88932Y-44763I-5953J5997D01*
G03X-89046Y-45725I65J-496D01*
G01X-87619Y-46273D01*
X-86454Y-48771D01*
X-86773Y-49787D01*
X-90342Y-51451D01*
X-91325Y-51043D01*
X-92490Y-48545D01*
X-91600Y-45958D01*
X-91020Y-45688D01*
G03X-91156Y-44741I-211J453D01*
G37*
G36*
G01X-134463D02*
G02X-127197Y-30498I1195J8365D01*
G02X-127315Y-42373I-6071J-5877D01*
G02X-132239Y-44763I-5953J5997D01*
G03X-132353Y-45725I65J-496D01*
G01X-130926Y-46273D01*
X-129761Y-48771D01*
X-130080Y-49787D01*
X-133649Y-51451D01*
X-134632Y-51043D01*
X-135797Y-48545D01*
X-134907Y-45958D01*
X-134327Y-45688D01*
G03X-134463Y-44741I-211J453D01*
G37*
G36*
G01X-21024Y-117826D02*
Y-129370D01*
G02X-44409I-11693J0D01*
G01Y-117826D01*
G02X-21024I11693J12078D01*
G37*
G36*
G01X-86773Y-64748D02*
X-90342Y-66412D01*
X-91325Y-66003D01*
X-92490Y-63505D01*
X-91600Y-60919D01*
X-90172Y-60253D01*
X-87619Y-61234D01*
X-86454Y-63732D01*
X-86773Y-64748D01*
G37*
G36*
G01X-90207Y-52047D02*
X-86678Y-50303D01*
X-85685Y-50689D01*
X-84464Y-53160D01*
X-85296Y-55766D01*
X-86708Y-56464D01*
X-89283Y-55541D01*
X-90504Y-53070D01*
X-90207Y-52047D01*
G37*
G36*
G01X-86773Y-79708D02*
X-90342Y-81372D01*
X-91325Y-80964D01*
X-92490Y-78466D01*
X-91600Y-75879D01*
X-90172Y-75214D01*
X-87619Y-76194D01*
X-86454Y-78692D01*
X-86773Y-79708D01*
G37*
G36*
G01X-90207Y-81968D02*
X-86678Y-80224D01*
X-85685Y-80610D01*
X-84464Y-83081D01*
X-85296Y-85687D01*
X-86708Y-86385D01*
X-89283Y-85462D01*
X-90504Y-82991D01*
X-90207Y-81968D01*
G37*
G36*
G01Y-67007D02*
X-86678Y-65263D01*
X-85685Y-65650D01*
X-84464Y-68121D01*
X-85296Y-70727D01*
X-86708Y-71424D01*
X-89283Y-70501D01*
X-90504Y-68030D01*
X-90207Y-67007D01*
G37*
G36*
G01X-86773Y-94669D02*
X-90342Y-96333D01*
X-91325Y-95924D01*
X-92490Y-93427D01*
X-91600Y-90840D01*
X-90172Y-90174D01*
X-87619Y-91155D01*
X-86454Y-93653D01*
X-86773Y-94669D01*
G37*
G36*
G01X-95632Y-49787D02*
X-99200Y-51451D01*
X-100184Y-51043D01*
X-101348Y-48545D01*
X-100458Y-45958D01*
X-99031Y-45293D01*
X-96477Y-46273D01*
X-95312Y-48771D01*
X-95632Y-49787D01*
G37*
G36*
G01X-99066Y-52047D02*
X-95536Y-50303D01*
X-94543Y-50689D01*
X-93323Y-53160D01*
X-94154Y-55766D01*
X-95566Y-56464D01*
X-98142Y-55541D01*
X-99362Y-53070D01*
X-99066Y-52047D01*
G37*
G36*
G01X-95632Y-64748D02*
X-99200Y-66412D01*
X-100184Y-66003D01*
X-101348Y-63505D01*
X-100458Y-60919D01*
X-99031Y-60253D01*
X-96477Y-61234D01*
X-95312Y-63732D01*
X-95632Y-64748D01*
G37*
G36*
G01X-99066Y-67007D02*
X-95536Y-65263D01*
X-94543Y-65650D01*
X-93323Y-68121D01*
X-94154Y-70727D01*
X-95566Y-71424D01*
X-98142Y-70501D01*
X-99362Y-68030D01*
X-99066Y-67007D01*
G37*
G36*
G01Y-81968D02*
X-95536Y-80224D01*
X-94543Y-80610D01*
X-93323Y-83081D01*
X-94154Y-85687D01*
X-95566Y-86385D01*
X-98142Y-85462D01*
X-99362Y-82991D01*
X-99066Y-81968D01*
G37*
G36*
G01X-95632Y-79708D02*
X-99200Y-81372D01*
X-100184Y-80964D01*
X-101348Y-78466D01*
X-100458Y-75879D01*
X-99031Y-75214D01*
X-96477Y-76194D01*
X-95312Y-78692D01*
X-95632Y-79708D01*
G37*
G36*
G01Y-94669D02*
X-99200Y-96333D01*
X-100184Y-95924D01*
X-101348Y-93427D01*
X-100458Y-90840D01*
X-99031Y-90174D01*
X-96477Y-91155D01*
X-95312Y-93653D01*
X-95632Y-94669D01*
G37*
G36*
G01X-133515Y-52047D02*
X-129985Y-50303D01*
X-128992Y-50689D01*
X-127771Y-53160D01*
X-128603Y-55766D01*
X-130015Y-56464D01*
X-132590Y-55541D01*
X-133811Y-53070D01*
X-133515Y-52047D01*
G37*
G36*
G01X-130080Y-64748D02*
X-133649Y-66412D01*
X-134632Y-66003D01*
X-135797Y-63505D01*
X-134907Y-60919D01*
X-133479Y-60253D01*
X-130926Y-61234D01*
X-129761Y-63732D01*
X-130080Y-64748D01*
G37*
G36*
G01X-142373Y-52047D02*
X-138843Y-50303D01*
X-137850Y-50689D01*
X-136630Y-53160D01*
X-137461Y-55766D01*
X-138874Y-56464D01*
X-141449Y-55541D01*
X-142669Y-53070D01*
X-142373Y-52047D01*
G37*
G36*
G01X-133515Y-67007D02*
X-129985Y-65263D01*
X-128992Y-65650D01*
X-127771Y-68121D01*
X-128603Y-70727D01*
X-130015Y-71424D01*
X-132590Y-70501D01*
X-133811Y-68030D01*
X-133515Y-67007D01*
G37*
G36*
G01Y-81968D02*
X-129985Y-80224D01*
X-128992Y-80610D01*
X-127771Y-83081D01*
X-128603Y-85687D01*
X-130015Y-86385D01*
X-132590Y-85462D01*
X-133811Y-82991D01*
X-133515Y-81968D01*
G37*
G36*
G01X-130080Y-79708D02*
X-133649Y-81372D01*
X-134632Y-80964D01*
X-135797Y-78466D01*
X-134907Y-75879D01*
X-133479Y-75214D01*
X-130926Y-76194D01*
X-129761Y-78692D01*
X-130080Y-79708D01*
G37*
G36*
G01X-142373Y-81968D02*
X-138843Y-80224D01*
X-137850Y-80610D01*
X-136630Y-83081D01*
X-137461Y-85687D01*
X-138874Y-86385D01*
X-141449Y-85462D01*
X-142669Y-82991D01*
X-142373Y-81968D01*
G37*
G36*
G01Y-67007D02*
X-138843Y-65263D01*
X-137850Y-65650D01*
X-136630Y-68121D01*
X-137461Y-70727D01*
X-138874Y-71424D01*
X-141449Y-70501D01*
X-142669Y-68030D01*
X-142373Y-67007D01*
G37*
G36*
G01X-130080Y-94669D02*
X-133649Y-96333D01*
X-134632Y-95924D01*
X-135797Y-93427D01*
X-134907Y-90840D01*
X-133479Y-90174D01*
X-130926Y-91155D01*
X-129761Y-93653D01*
X-130080Y-94669D01*
G37*
G36*
G01X-138939Y-49787D02*
X-142507Y-51451D01*
X-143491Y-51043D01*
X-144655Y-48545D01*
X-143765Y-45958D01*
X-142338Y-45293D01*
X-139784Y-46273D01*
X-138619Y-48771D01*
X-138939Y-49787D01*
G37*
G36*
G01Y-64748D02*
X-142507Y-66412D01*
X-143491Y-66003D01*
X-144655Y-63505D01*
X-143765Y-60919D01*
X-142338Y-60253D01*
X-139784Y-61234D01*
X-138619Y-63732D01*
X-138939Y-64748D01*
G37*
G36*
G01Y-79708D02*
X-142507Y-81372D01*
X-143491Y-80964D01*
X-144655Y-78466D01*
X-143765Y-75879D01*
X-142338Y-75214D01*
X-139784Y-76194D01*
X-138619Y-78692D01*
X-138939Y-79708D01*
G37*
G36*
G01Y-94669D02*
X-142507Y-96333D01*
X-143491Y-95924D01*
X-144655Y-93427D01*
X-143765Y-90840D01*
X-142338Y-90174D01*
X-139784Y-91155D01*
X-138619Y-93653D01*
X-138939Y-94669D01*
G37*
G36*
G01X-293268Y-80818D02*
Y-92362D01*
G02X-316654I-11693J0D01*
G01Y-80818D01*
G02X-293268I11693J12078D01*
G37*
G36*
G01X-240725Y-121879D02*
X-240744Y-121702D01*
Y-118409D01*
X-240725Y-118232D01*
G02X-236543Y-118618I2088J-223D01*
G01X-236544Y-118627D01*
Y-121483D01*
X-236543Y-121493D01*
G02X-240725Y-121879I-2094J-162D01*
G37*
G36*
G01X-363438Y-132269D02*
X-363260Y-132250D01*
X-359968D01*
X-359791Y-132269D01*
G02X-360176Y-136451I-223J-2088D01*
G01X-360186Y-136450D01*
X-363042D01*
X-363051Y-136451D01*
G02X-363438Y-132269I-162J2094D01*
G37*
G36*
G01X-324681Y-141597D02*
Y-143638D01*
X-329181D01*
Y-141590D01*
G02Y-139197I2252J1197D01*
G01Y-136079D01*
G02Y-133685I2252J1197D01*
G01Y-131638D01*
X-324681D01*
Y-133679D01*
G02Y-136085I-2248J-1203D01*
G01Y-139190D01*
G02Y-141597I-2248J-1203D01*
G37*
G36*
G01X-110663Y-141594D02*
Y-143638D01*
X-115163D01*
Y-141594D01*
G02Y-139194I2250J1200D01*
G01Y-136082D01*
G02Y-133682I2250J1200D01*
G01Y-131638D01*
X-110663D01*
Y-133682D01*
G02Y-136082I-2250J-1200D01*
G01Y-139194D01*
G02Y-141594I-2250J-1200D01*
G37*
G36*
G01X-126411D02*
Y-143638D01*
X-130911D01*
Y-141594D01*
G02Y-139194I2250J1200D01*
G01Y-136082D01*
G02Y-133682I2250J1200D01*
G01Y-131638D01*
X-126411D01*
Y-133682D01*
G02Y-136082I-2250J-1200D01*
G01Y-139194D01*
G02Y-141594I-2250J-1200D01*
G37*
G36*
G01X-142159D02*
Y-143638D01*
X-146659D01*
Y-141594D01*
G02Y-139194I2250J1200D01*
G01Y-136082D01*
G02Y-133682I2250J1200D01*
G01Y-131638D01*
X-142159D01*
Y-133682D01*
G02Y-136082I-2250J-1200D01*
G01Y-139194D01*
G02Y-141594I-2250J-1200D01*
G37*
G36*
G01X-391770Y-142354D02*
X-391593Y-142335D01*
X-388300D01*
X-388123Y-142354D01*
G02X-388509Y-146536I-223J-2088D01*
G01X-388518Y-146535D01*
X-391374D01*
X-391384Y-146536D01*
G02X-391770Y-142354I-162J2094D01*
G37*
G36*
G01X-102789Y-146712D02*
Y-148756D01*
X-107289D01*
Y-146712D01*
G02Y-144312I2250J1200D01*
G01Y-141200D01*
G02Y-138800I2250J1200D01*
G01Y-136756D01*
X-102789D01*
Y-138800D01*
G02Y-141200I-2250J-1200D01*
G01Y-144312D01*
G02Y-146712I-2250J-1200D01*
G37*
G36*
G01X-118537D02*
Y-148756D01*
X-123037D01*
Y-146712D01*
G02Y-144312I2250J1200D01*
G01Y-141200D01*
G02Y-138800I2250J1200D01*
G01Y-136756D01*
X-118537D01*
Y-138800D01*
G02Y-141200I-2250J-1200D01*
G01Y-144312D01*
G02Y-146712I-2250J-1200D01*
G37*
G36*
G01X-134285D02*
Y-148756D01*
X-138785D01*
Y-146712D01*
G02Y-144312I2250J1200D01*
G01Y-141200D01*
G02Y-138800I2250J1200D01*
G01Y-136756D01*
X-134285D01*
Y-138800D01*
G02Y-141200I-2250J-1200D01*
G01Y-144312D01*
G02Y-146712I-2250J-1200D01*
G37*
G36*
G01X-285311Y-146715D02*
Y-148756D01*
X-289811D01*
Y-146709D01*
G02Y-144315I2252J1197D01*
G01Y-141197D01*
G02Y-138803I2252J1197D01*
G01Y-136756D01*
X-285311D01*
Y-138797D01*
G02Y-141203I-2248J-1203D01*
G01Y-144309D01*
G02Y-146715I-2248J-1203D01*
G37*
G36*
G01X-401233Y-149699D02*
X-401056Y-149680D01*
X-397763D01*
X-397586Y-149699D01*
G02X-397971Y-153881I-223J-2088D01*
G01X-397981Y-153880D01*
X-400837D01*
X-400847Y-153881D01*
G02X-401233Y-149699I-162J2094D01*
G37*
G36*
G01X-324681Y-158132D02*
Y-160173D01*
X-329181D01*
Y-158126D01*
G02Y-155732I2252J1197D01*
G01Y-152614D01*
G02Y-150221I2252J1197D01*
G01Y-148173D01*
X-324681D01*
Y-150214D01*
G02Y-152621I-2248J-1203D01*
G01Y-155726D01*
G02Y-158132I-2248J-1203D01*
G37*
G36*
G01X-110663Y-158129D02*
Y-160173D01*
X-115163D01*
Y-158129D01*
G02Y-155729I2250J1200D01*
G01Y-152617D01*
G02Y-150217I2250J1200D01*
G01Y-148173D01*
X-110663D01*
Y-150217D01*
G02Y-152617I-2250J-1200D01*
G01Y-155729D01*
G02Y-158129I-2250J-1200D01*
G37*
G36*
G01X-126411D02*
Y-160173D01*
X-130911D01*
Y-158129D01*
G02Y-155729I2250J1200D01*
G01Y-152617D01*
G02Y-150217I2250J1200D01*
G01Y-148173D01*
X-126411D01*
Y-150217D01*
G02Y-152617I-2250J-1200D01*
G01Y-155729D01*
G02Y-158129I-2250J-1200D01*
G37*
G36*
G01X-142159D02*
Y-160173D01*
X-146659D01*
Y-158129D01*
G02Y-155729I2250J1200D01*
G01Y-152617D01*
G02Y-150217I2250J1200D01*
G01Y-148173D01*
X-142159D01*
Y-150217D01*
G02Y-152617I-2250J-1200D01*
G01Y-155729D01*
G02Y-158129I-2250J-1200D01*
G37*
G36*
G01X-102789Y-163247D02*
Y-165291D01*
X-107289D01*
Y-163247D01*
G02Y-160847I2250J1200D01*
G01Y-157735D01*
G02Y-155335I2250J1200D01*
G01Y-153291D01*
X-102789D01*
Y-155335D01*
G02Y-157735I-2250J-1200D01*
G01Y-160847D01*
G02Y-163247I-2250J-1200D01*
G37*
G36*
G01X-118537D02*
Y-165291D01*
X-123037D01*
Y-163247D01*
G02Y-160847I2250J1200D01*
G01Y-157735D01*
G02Y-155335I2250J1200D01*
G01Y-153291D01*
X-118537D01*
Y-155335D01*
G02Y-157735I-2250J-1200D01*
G01Y-160847D01*
G02Y-163247I-2250J-1200D01*
G37*
G36*
G01X-134285D02*
Y-165291D01*
X-138785D01*
Y-163247D01*
G02Y-160847I2250J1200D01*
G01Y-157735D01*
G02Y-155335I2250J1200D01*
G01Y-153291D01*
X-134285D01*
Y-155335D01*
G02Y-157735I-2250J-1200D01*
G01Y-160847D01*
G02Y-163247I-2250J-1200D01*
G37*
G36*
G01X-285311Y-163250D02*
Y-165291D01*
X-289811D01*
Y-163244D01*
G02Y-160850I2252J1197D01*
G01Y-157732D01*
G02Y-155339I2252J1197D01*
G01Y-153291D01*
X-285311D01*
Y-155332D01*
G02Y-157739I-2248J-1203D01*
G01Y-160844D01*
G02Y-163250I-2248J-1203D01*
G37*
G36*
G01X-339565Y-165279D02*
X-339388Y-165260D01*
X-336095D01*
X-335918Y-165279D01*
G02X-336303Y-169461I-223J-2088D01*
G01X-336313Y-169460D01*
X-339169D01*
X-339178Y-169461D01*
G02X-339565Y-165279I-162J2094D01*
G37*
G36*
G01X-110663Y-174665D02*
Y-176709D01*
X-115163D01*
Y-174665D01*
G02Y-172265I2250J1200D01*
G01Y-169153D01*
G02Y-166753I2250J1200D01*
G01Y-164709D01*
X-110663D01*
Y-166753D01*
G02Y-169153I-2250J-1200D01*
G01Y-172265D01*
G02Y-174665I-2250J-1200D01*
G37*
G36*
G01X-142159D02*
Y-176709D01*
X-146659D01*
Y-174665D01*
G02Y-172265I2250J1200D01*
G01Y-169153D01*
G02Y-166753I2250J1200D01*
G01Y-164709D01*
X-142159D01*
Y-166753D01*
G02Y-169153I-2250J-1200D01*
G01Y-172265D01*
G02Y-174665I-2250J-1200D01*
G37*
G36*
G01X-293185Y-174668D02*
Y-176709D01*
X-297685D01*
Y-174661D01*
G02Y-172268I2252J1197D01*
G01Y-169150D01*
G02Y-166756I2252J1197D01*
G01Y-164709D01*
X-293185D01*
Y-166750D01*
G02Y-169156I-2248J-1203D01*
G01Y-172261D01*
G02Y-174668I-2248J-1203D01*
G37*
G36*
G01X-308933D02*
Y-176709D01*
X-313433D01*
Y-174661D01*
G02Y-172268I2252J1197D01*
G01Y-169150D01*
G02Y-166756I2252J1197D01*
G01Y-164709D01*
X-308933D01*
Y-166750D01*
G02Y-169156I-2248J-1203D01*
G01Y-172261D01*
G02Y-174668I-2248J-1203D01*
G37*
G36*
G01X-324681D02*
Y-176709D01*
X-329181D01*
Y-174661D01*
G02Y-172268I2252J1197D01*
G01Y-169150D01*
G02Y-166756I2252J1197D01*
G01Y-164709D01*
X-324681D01*
Y-166750D01*
G02Y-169156I-2248J-1203D01*
G01Y-172261D01*
G02Y-174668I-2248J-1203D01*
G37*
G36*
G01X-102789Y-179783D02*
Y-181827D01*
X-107289D01*
Y-179783D01*
G02Y-177383I2250J1200D01*
G01Y-174271D01*
G02Y-171871I2250J1200D01*
G01Y-169827D01*
X-102789D01*
Y-171871D01*
G02Y-174271I-2250J-1200D01*
G01Y-177383D01*
G02Y-179783I-2250J-1200D01*
G37*
G36*
G01X-134285D02*
Y-181827D01*
X-138785D01*
Y-179783D01*
G02Y-177383I2250J1200D01*
G01Y-174271D01*
G02Y-171871I2250J1200D01*
G01Y-169827D01*
X-134285D01*
Y-171871D01*
G02Y-174271I-2250J-1200D01*
G01Y-177383D01*
G02Y-179783I-2250J-1200D01*
G37*
G36*
G01X-285311Y-179786D02*
Y-181827D01*
X-289811D01*
Y-179779D01*
G02Y-177386I2252J1197D01*
G01Y-174268D01*
G02Y-171874I2252J1197D01*
G01Y-169827D01*
X-285311D01*
Y-171868D01*
G02Y-174274I-2248J-1203D01*
G01Y-177379D01*
G02Y-179786I-2248J-1203D01*
G37*
G36*
G01X-301059D02*
Y-181827D01*
X-305559D01*
Y-179779D01*
G02Y-177386I2252J1197D01*
G01Y-174268D01*
G02Y-171874I2252J1197D01*
G01Y-169827D01*
X-301059D01*
Y-171868D01*
G02Y-174274I-2248J-1203D01*
G01Y-177379D01*
G02Y-179786I-2248J-1203D01*
G37*
G36*
G01X-316807D02*
Y-181827D01*
X-321307D01*
Y-179779D01*
G02Y-177386I2252J1197D01*
G01Y-174268D01*
G02Y-171874I2252J1197D01*
G01Y-169827D01*
X-316807D01*
Y-171868D01*
G02Y-174274I-2248J-1203D01*
G01Y-177379D01*
G02Y-179786I-2248J-1203D01*
G37*
G36*
G01X-399658Y-181556D02*
X-399481Y-181537D01*
X-396188D01*
X-396011Y-181556D01*
G02X-396397Y-185738I-223J-2088D01*
G01X-396406Y-185737D01*
X-399262D01*
X-399272Y-185738D01*
G02X-399658Y-181556I-162J2094D01*
G37*
G36*
G01X-365685Y-183299D02*
X-365508Y-183280D01*
X-362215D01*
X-362038Y-183299D01*
G02X-362423Y-187481I-223J-2088D01*
G01X-362433Y-187480D01*
X-365289D01*
X-365298Y-187481D01*
G02X-365685Y-183299I-162J2094D01*
G37*
G36*
G01X-377732Y-190129D02*
X-377751Y-189952D01*
Y-186659D01*
X-377732Y-186482D01*
G02X-373550Y-186868I2088J-223D01*
G01X-373551Y-186877D01*
Y-189733D01*
X-373550Y-189743D01*
G02X-377732Y-190129I-2094J-162D01*
G37*
G36*
G01X-388872Y-125896D02*
G02X-390538Y-125817I-898J-1324D01*
G03X-390498Y-124964I-240J439D01*
G02X-388832Y-125043I898J1324D01*
G03X-388872Y-125896I240J-439D01*
G37*
G36*
G01X-294341Y-138090D02*
G02X-296526I-1093J-2304D01*
G03Y-137186I-214J452D01*
G02X-294341I1093J2304D01*
G03Y-138090I214J-452D01*
G37*
G36*
G01X-317963Y-143208D02*
G02X-320148I-1093J-2304D01*
G03Y-142304I-214J452D01*
G02Y-137696I1093J2304D01*
G03Y-136792I-214J452D01*
G02X-317963I1093J2304D01*
G03Y-137696I214J-452D01*
G02Y-142304I-1093J-2304D01*
G03Y-143208I214J-452D01*
G37*
G36*
G01X-294341Y-154625D02*
G02X-296526I-1093J-2304D01*
G03Y-153721I-214J452D01*
G02X-294341I1093J2304D01*
G03Y-154625I214J-452D01*
G37*
G36*
G01X-310089D02*
G02X-312274I-1093J-2304D01*
G03Y-153721I-214J452D01*
G02Y-149113I1093J2304D01*
G03Y-148210I-214J452D01*
G02Y-143601I1093J2304D01*
G03Y-142698I-214J452D01*
G02Y-138090I1093J2304D01*
G03Y-137186I-214J452D01*
G02X-310089I1093J2304D01*
G03Y-138090I214J-452D01*
G02Y-142698I-1093J-2304D01*
G03Y-143601I214J-452D01*
G02Y-148210I-1093J-2304D01*
G03Y-149113I214J-452D01*
G02Y-153721I-1093J-2304D01*
G03Y-154625I214J-452D01*
G37*
G36*
G01X-302215Y-159743D02*
G02X-304400I-1093J-2304D01*
G03Y-158840I-214J452D01*
G02Y-154231I1093J2304D01*
G03Y-153328I-214J452D01*
G02Y-148720I1093J2304D01*
G03Y-147816I-214J452D01*
G02Y-143208I1093J2304D01*
G03Y-142304I-214J452D01*
G02Y-137696I1093J2304D01*
G03Y-136792I-214J452D01*
G02X-302215I1093J2304D01*
G03Y-137696I214J-452D01*
G02Y-142304I-1093J-2304D01*
G03Y-143208I214J-452D01*
G02Y-147816I-1093J-2304D01*
G03Y-148720I214J-452D01*
G02Y-153328I-1093J-2304D01*
G03Y-154231I214J-452D01*
G02Y-158840I-1093J-2304D01*
G03Y-159743I214J-452D01*
G37*
G36*
G01X-317963D02*
G02X-320148I-1093J-2304D01*
G03Y-158840I-214J452D01*
G02X-317963I1093J2304D01*
G03Y-159743I214J-452D01*
G37*
G36*
G01X-127569Y-171160D02*
G02X-129754I-1093J-2304D01*
G03Y-170257I-214J452D01*
G02X-127569I1093J2304D01*
G03Y-171160I214J-452D01*
G37*
G36*
G01X-276690Y-178957D02*
G02Y-177443I-1410J757D01*
G03X-275810I440J237D01*
G02Y-178957I1410J-757D01*
G03X-276690I-440J-237D01*
G37*
G36*
G01X-119695Y-176279D02*
G02X-121880I-1093J-2304D01*
G03Y-175375I-214J452D01*
G02X-119695I1093J2304D01*
G03Y-176279I214J-452D01*
G37*
G36*
G01X-404627Y-181766D02*
G02X-406453I-913J-1314D01*
G03Y-180944I-285J411D01*
G02X-404627I913J1314D01*
G03Y-181766I285J-411D01*
G37*
G36*
G01X-235571Y-136850D02*
X-230171D01*
X-229171Y-137850D01*
Y-146850D01*
X-230171Y-147850D01*
X-235571D01*
X-236571Y-146850D01*
Y-137850D01*
X-235571Y-136850D01*
G37*
G36*
G01X-254469D02*
X-249069D01*
X-248069Y-137850D01*
Y-146850D01*
X-249069Y-147850D01*
X-254469D01*
X-255469Y-146850D01*
Y-137850D01*
X-254469Y-136850D01*
G37*
G36*
G01X-253595Y-153102D02*
X-253418Y-153083D01*
X-250125D01*
X-249948Y-153102D01*
G02X-250334Y-157284I-223J-2088D01*
G01X-250343Y-157283D01*
X-253199D01*
X-253209Y-157284D01*
G02X-253595Y-153102I-162J2094D01*
G37*
G36*
G01X-141449Y-100423D02*
X-142669Y-97952D01*
X-142373Y-96928D01*
X-138843Y-95185D01*
X-137850Y-95571D01*
X-136630Y-98042D01*
X-137461Y-100648D01*
X-138874Y-101346D01*
X-141449Y-100423D01*
G37*
G36*
G01X-132590D02*
X-133811Y-97952D01*
X-133515Y-96928D01*
X-129985Y-95185D01*
X-128992Y-95571D01*
X-127771Y-98042D01*
X-128603Y-100648D01*
X-130015Y-101346D01*
X-132590Y-100423D01*
G37*
G36*
G01X-98142D02*
X-99362Y-97952D01*
X-99066Y-96928D01*
X-95536Y-95185D01*
X-94543Y-95571D01*
X-93323Y-98042D01*
X-94154Y-100648D01*
X-95566Y-101346D01*
X-98142Y-100423D01*
G37*
G36*
G01X-89283D02*
X-90504Y-97952D01*
X-90207Y-96928D01*
X-86678Y-95185D01*
X-85685Y-95571D01*
X-84464Y-98042D01*
X-85296Y-100648D01*
X-86708Y-101346D01*
X-89283Y-100423D01*
G37*
G54D35*
X-1530000Y-120300D03*
X-1497000Y-81700D03*
X-1496693Y-76890D03*
Y-71890D03*
X-1486693D03*
X-1491693D03*
X-1476693D03*
X-1481693D03*
X-1471693D03*
X-1476693Y-76890D03*
X-1481693D03*
X-1471693D03*
X-1466693D03*
Y-81890D03*
Y-71890D03*
X-1461693Y-76890D03*
X-1658500Y-31000D03*
X-1639488Y-27500D03*
X-1644488D03*
X-1654488Y-27300D03*
X-1649488Y-27400D03*
X-1634488Y-27600D03*
X-1629488Y-27700D03*
X-1535063Y-22160D03*
X-1530063Y-12160D03*
Y-17160D03*
Y-22160D03*
X-1535063Y-12160D03*
Y-17160D03*
X-1515063Y-12160D03*
Y-17160D03*
Y-22160D03*
X-1525063Y-12160D03*
Y-17160D03*
X-1520063Y-12160D03*
Y-17160D03*
X-1525063Y-22160D03*
X-1520063D03*
X-1500063Y-12160D03*
Y-17160D03*
Y-22160D03*
X-1510063Y-12160D03*
Y-17160D03*
X-1505063Y-12160D03*
Y-17160D03*
X-1510063Y-22160D03*
X-1505063D03*
X-1485063Y-12160D03*
Y-17160D03*
Y-22160D03*
X-1495063Y-12160D03*
Y-17160D03*
X-1490063Y-12160D03*
Y-17160D03*
X-1495063Y-22160D03*
X-1490063D03*
X-1475063D03*
X-1470063Y-12160D03*
Y-17160D03*
Y-22160D03*
X-1480063Y-12160D03*
Y-17160D03*
X-1475063Y-12160D03*
Y-17160D03*
X-1480063Y-22160D03*
X-1450000Y-112500D03*
X-1465063Y-12160D03*
Y-17160D03*
Y-22160D03*
X-1437500Y-175000D03*
X-1450000Y-162500D03*
Y-137500D03*
X-1437500Y-100000D03*
X-1436500Y-87500D03*
X-1450000D03*
X-1448900Y-76100D03*
X-1435000Y1000D03*
X-1425000Y-162500D03*
X-1430500Y-93500D03*
X-1430000Y-75400D03*
X-1421250Y-81250D03*
X-1431500Y-81000D03*
X-1419500Y-18000D03*
X-1420000Y14500D03*
X-1412500Y-175000D03*
X-1406250Y-106250D03*
X-1412000Y-100500D03*
X-1418500Y-93500D03*
X-1406250Y-82500D03*
X-1412500Y-62500D03*
X-1387500Y-175000D03*
Y-150000D03*
X-1400000Y-162500D03*
X-1387300Y-133200D03*
X-1387500Y-125000D03*
X-1400100Y-131550D03*
X-1395000Y-106250D03*
X-1400000Y-112500D03*
X-1400500Y-96500D03*
X-1393750Y-82500D03*
X-1400000Y-75000D03*
X-1387500Y-62500D03*
X-1394500Y-18000D03*
X-1395000Y-500D03*
X-1395518Y14053D03*
X-1371250Y-112500D03*
X-1380000Y-106250D03*
X-1381250Y-82500D03*
X-1375000Y-75000D03*
X-1373800Y-52900D03*
X-1382500Y-8000D03*
Y7000D03*
X-1363750Y-106250D03*
X-1356250Y-82500D03*
X-1368750D03*
X-1362500Y-62500D03*
X-1356700Y-25600D03*
X-1357500Y-8000D03*
X-1370000Y-500D03*
X-1357500Y7000D03*
X-1370000Y14500D03*
X-1350600Y-75000D03*
X-1343200Y-82700D03*
X-1345000Y-500D03*
Y14500D03*
X-1330400Y-74900D03*
X-1324840Y-82120D03*
X-1337500Y-62500D03*
X-1324500Y-26959D03*
X-1332500Y-27500D03*
Y7000D03*
X-1321000Y-94850D03*
X-1313040Y-80810D03*
X-1317700Y-72700D03*
X-1310559Y-74200D03*
X-1317700Y-60200D03*
X-1310559Y-68700D03*
Y-63200D03*
Y-57700D03*
X-1310600Y-46690D03*
X-1310559Y-41200D03*
Y-52200D03*
X-1311200Y-30200D03*
X-1310559Y-35700D03*
X-1320000Y-500D03*
X-1318500Y-6000D03*
X-1320000Y14500D03*
X-1306850Y-95000D03*
X-1300350Y-88500D03*
X-1302400Y-84100D03*
X-1297995Y-58405D03*
X-1298400Y-63200D03*
X-1298780Y-52200D03*
X-1298000Y-41200D03*
X-1298700Y-35700D03*
X-1298800Y-30200D03*
X-1295400Y-13400D03*
X-1307500Y7000D03*
X-1295000Y14500D03*
X-1270000D03*
X-1257500Y-57500D03*
X-1245000Y-70000D03*
X-1232500Y-57500D03*
Y-45000D03*
X-1245000D03*
Y-20000D03*
Y14500D03*
X-1220000D03*
X-1202100Y-103200D03*
X-1199500Y5400D03*
X-1191200Y-40500D03*
X-1191000Y-46500D03*
X-1191500Y-34000D03*
X-1191900Y-29500D03*
X-1190800Y-23450D03*
X-1191000Y-18250D03*
X-1191200Y-12128D03*
X-1192359Y-5800D03*
X-1191500Y0D03*
X-1195000Y14500D03*
X-1172500Y-44000D03*
X-1173200Y-49700D03*
X-1178900Y-46700D03*
X-1179000Y-40500D03*
X-1172500Y-38500D03*
X-1178950Y-23250D03*
X-1171800Y-26950D03*
X-1178800Y-34800D03*
X-1177800Y-12100D03*
X-1172000Y-10750D03*
X-1171500Y-21750D03*
X-1171800Y-16250D03*
X-1178800Y-5800D03*
X-1172100Y-5400D03*
X-1170000Y14500D03*
X-1160000Y-38500D03*
X-1159700Y-43900D03*
X-1160150Y-26750D03*
X-1159800Y-33100D03*
X-1158700Y-16250D03*
X-1159700Y-5750D03*
X-1137500Y-2500D03*
X-1145000Y14500D03*
X-1126000Y-15000D03*
X-1120000Y14500D03*
X-1107700Y-73400D03*
Y-63100D03*
X-1107800Y-68200D03*
X-1111500Y-2500D03*
X-1099400Y-90200D03*
X-1093400D03*
X-1100000Y-15000D03*
X-1095000Y14500D03*
X-1073000Y-90300D03*
X-1056900Y-56300D03*
X-1063600Y-56600D03*
X-1062000Y-29200D03*
X-1061900Y-5200D03*
X-1045100Y-52900D03*
X-1044300Y-47661D03*
X-1051200Y-44100D03*
X-1054900Y-29800D03*
X-1045400Y-38000D03*
X-1051400Y-26000D03*
X-1047289Y-26300D03*
X-1041300Y-10100D03*
Y-16500D03*
X-1054600Y-5100D03*
X-1050811Y2600D03*
X-1047300Y-2700D03*
X-1032500Y14500D03*
X-1012500Y-7500D03*
X-1007500Y14500D03*
X-983000Y-7500D03*
X-982500Y14500D03*
X-957500Y-7500D03*
Y14500D03*
X-932500Y-7500D03*
Y14500D03*
X-922500Y-170000D03*
Y-120000D03*
Y-95000D03*
Y-70000D03*
Y-45000D03*
Y-20000D03*
Y5000D03*
X-910000Y-159500D03*
Y-132500D03*
Y-107500D03*
Y-82500D03*
Y-57500D03*
Y-7500D03*
X-909500Y14500D03*
X-897500Y-170000D03*
X-885000Y-159500D03*
Y-132500D03*
Y-107500D03*
X-897500Y-95000D03*
X-885000Y-82500D03*
X-897500Y-70000D03*
X-885000Y-57500D03*
X-897500Y-45000D03*
X-885000Y-7500D03*
X-897500Y-20000D03*
Y5000D03*
X-885000Y14500D03*
X-872500Y-170000D03*
Y-95000D03*
Y-70000D03*
Y-45000D03*
Y-20000D03*
Y5000D03*
X-860000Y-159500D03*
Y-132500D03*
Y-107500D03*
Y-82500D03*
Y-57500D03*
Y-7500D03*
Y14500D03*
X-847500Y-170000D03*
Y-95000D03*
Y-70000D03*
Y-45000D03*
Y-20000D03*
Y5000D03*
X-822500Y-170000D03*
X-835000Y-159500D03*
X-822500Y-145000D03*
X-835000Y-132500D03*
X-822500Y-120000D03*
X-835000Y-107500D03*
X-822500Y-95000D03*
X-835000Y-82500D03*
X-822500Y-70000D03*
X-835000Y-57500D03*
X-822500Y-45000D03*
Y-20000D03*
Y5000D03*
X-835500Y14500D03*
X-810000Y-170000D03*
Y-157500D03*
Y-145000D03*
Y-132500D03*
Y-120000D03*
Y-70000D03*
Y-57500D03*
Y-45000D03*
Y-7500D03*
Y14500D03*
X-797500Y-120000D03*
Y-70000D03*
Y-57500D03*
Y-45000D03*
Y-20000D03*
Y5000D03*
X-785500Y-120000D03*
X-785000Y-70000D03*
Y-57500D03*
Y-45000D03*
Y-7500D03*
Y14500D03*
X-772500Y-170000D03*
Y-145000D03*
Y-120000D03*
Y-95000D03*
Y-70000D03*
Y-45000D03*
X-760000Y-7500D03*
X-772500Y-20000D03*
Y5000D03*
X-760000Y14500D03*
X-747500Y-45000D03*
Y-20000D03*
Y5000D03*
X-735000Y-7500D03*
Y14500D03*
X-722500Y-45000D03*
Y-20000D03*
Y5000D03*
X-697500Y-45000D03*
Y-20000D03*
X-710000Y-7500D03*
X-697500Y5000D03*
X-710000Y14500D03*
X-685000Y-7500D03*
Y14500D03*
X-672500Y-45000D03*
Y-20000D03*
Y5000D03*
X-655500Y-37500D03*
Y-12500D03*
Y-500D03*
X-660000Y14500D03*
X-632500D03*
X-616000Y-37500D03*
X-630000Y-25500D03*
Y-12500D03*
X-616000D03*
Y14500D03*
X-602500Y-37500D03*
Y-12500D03*
Y12500D03*
X-590000Y-25000D03*
Y0D03*
X-577500Y-177500D03*
Y-152500D03*
Y-127500D03*
Y-37500D03*
Y-12500D03*
Y12500D03*
X-565000Y-165000D03*
Y-140000D03*
Y-65000D03*
Y-25000D03*
Y0D03*
X-540000Y-165000D03*
X-552500Y-177500D03*
Y-152500D03*
X-540000Y-140000D03*
Y-115000D03*
Y-90000D03*
Y-65000D03*
Y-25000D03*
X-552500Y-37500D03*
Y-12500D03*
X-540000Y0D03*
X-552500Y12500D03*
X-527500Y-177500D03*
Y-152500D03*
Y-127500D03*
Y-102500D03*
Y-77500D03*
Y-37500D03*
Y-12500D03*
Y12500D03*
X-515000Y-165000D03*
Y-140000D03*
Y-115000D03*
Y-90000D03*
Y-65000D03*
Y-25000D03*
Y0D03*
X-502500Y-102500D03*
X-490000Y-90000D03*
X-502500Y-77500D03*
Y-37500D03*
Y-12500D03*
X-490000Y0D03*
X-502500Y12500D03*
X-486421Y-26159D03*
X-477500Y-37500D03*
Y12500D03*
X-465000Y-25000D03*
X-461441Y6559D03*
X-456240Y-82020D03*
X-444440Y-80710D03*
X-452700Y-69000D03*
X-449100Y-60841D03*
X-442800Y-46600D03*
X-454421Y-26959D03*
X-443941Y6559D03*
X-448600Y-5900D03*
X-452500Y12500D03*
X-432118Y-87082D03*
X-436771Y-92400D03*
X-441959Y-74100D03*
X-429900Y-79600D03*
X-441959Y-68600D03*
X-429000Y-57600D03*
X-430700Y-63100D03*
X-441959D03*
Y-57600D03*
X-430180Y-52100D03*
X-429400Y-41100D03*
X-441959D03*
Y-52100D03*
X-430400Y-35600D03*
X-442000Y-29480D03*
X-441959Y-35600D03*
X-427500Y12500D03*
X-424600Y-14400D03*
X-1248860Y-150200D03*
X-1246390Y-153490D03*
X-1249016Y-144800D03*
X-1250660Y-140480D03*
X-1236310Y-140390D03*
X-1202580Y-176300D03*
X-1176100Y-114800D03*
X-1170300Y-114600D03*
X-1160000Y-115100D03*
X-1017670Y-123250D03*
X-1022140Y-122960D03*
X-747500Y-57500D03*
X-735000D03*
X-722500D03*
X-649700Y-117200D03*
X-596614Y-81890D03*
X-380421Y-147000D03*
X-375800Y-154000D03*
X-373620Y-124430D03*
X-374800Y-105700D03*
X-333450Y-174950D03*
X-321600Y-113500D03*
X-316500D03*
X-321700Y-42000D03*
X-321500Y-47500D03*
X-322400Y-31000D03*
X-321300Y-24950D03*
X-321800Y-7300D03*
X-321700Y-13628D03*
X-321859Y-1500D03*
X-312100Y-113500D03*
X-303200Y-43300D03*
Y-48800D03*
X-309400Y-47700D03*
X-302300Y-25950D03*
X-302900Y-37900D03*
X-309400Y-25100D03*
X-308500Y-36400D03*
X-308800Y-7400D03*
X-302500Y-15200D03*
X-307900Y-13628D03*
X-302300Y-4450D03*
X-286500Y-113700D03*
X-296400Y-113500D03*
X-290400Y-43200D03*
X-289500Y-32500D03*
X-290800Y-26000D03*
X-290700Y-9750D03*
X-290300Y-4400D03*
X-282300Y-113700D03*
X-254800Y-180000D03*
X-265200Y-179850D03*
X-237750Y-182300D03*
X-243250Y-182209D03*
X-244900Y-170700D03*
X-244300Y-129300D03*
X-240300D03*
X-245411Y-104240D03*
X-248622Y-101759D03*
X-251792Y-104330D03*
X-242323Y-101600D03*
X-239222Y-104200D03*
X-225400Y-179800D03*
X-236900Y-170700D03*
X-236024Y-102100D03*
X-232874Y-104200D03*
X-214500Y-179800D03*
X-196900Y-176500D03*
X-201600Y-176600D03*
X-206100D03*
X-191000Y-56400D03*
X-190300Y-28900D03*
Y-4200D03*
X-185900Y-56200D03*
X-179800Y-43500D03*
X-182900Y-29800D03*
X-176350Y-27200D03*
X-179811Y-21300D03*
X-183200Y-4600D03*
X-179011Y4500D03*
X-175100Y-1800D03*
X-163764Y-128576D03*
X-173800Y-47300D03*
X-173200Y-52400D03*
X-170200Y-34470D03*
X-170500Y-10000D03*
X-170300Y-16500D03*
X-150900Y-121100D03*
X-152400Y-125050D03*
X-254921Y-101700D03*
G54D34*
X-1615984Y-156535D03*
G54D39*
X-1282480Y-130157D03*
Y-94724D03*
Y-59291D03*
Y-23858D03*
X-1207677Y-77008D03*
Y-41575D03*
Y-6142D03*
G54D41*
X-1025000Y1459D03*
X-981693D03*
X-938386D03*
G54D43*
X-994488Y-93068D03*
Y-78108D03*
Y-63147D03*
Y-48187D03*
X-991535Y-98580D03*
Y-83620D03*
Y-68659D03*
Y-53698D03*
X-951181Y-93068D03*
X-948228Y-98580D03*
Y-83620D03*
X-951181Y-78108D03*
X-948228Y-68659D03*
X-951181Y-63147D03*
X-948228Y-53698D03*
X-951181Y-48187D03*
X-124409Y-93068D03*
X-121457Y-83620D03*
X-124409Y-78108D03*
X-121457Y-68659D03*
X-124409Y-63147D03*
X-121457Y-53698D03*
X-124409Y-48187D03*
X-81102Y-93068D03*
Y-78108D03*
Y-63147D03*
Y-48187D03*
X-78150Y-83620D03*
Y-68659D03*
Y-53698D03*
Y-98580D03*
X-121457D03*
G54D32*
X-1649000Y-105752D03*
Y-113626D03*
X-793728Y-153976D03*
Y-146102D03*
G54D31*
X-1649000Y-121500D03*
X-1327756Y-175039D03*
Y-167165D03*
Y-159291D03*
Y-143543D03*
Y-135669D03*
Y-127795D03*
X-1319882Y-175039D03*
Y-167165D03*
Y-159291D03*
Y-135669D03*
Y-127795D03*
X-793728Y-161850D03*
Y-138228D03*
X-457677Y-175039D03*
Y-167165D03*
Y-159291D03*
Y-143543D03*
Y-135669D03*
Y-127795D03*
X-449803Y-175039D03*
Y-167165D03*
Y-159291D03*
Y-135669D03*
Y-127795D03*
G54D33*
X-1649000Y-97878D03*
G54D36*
X-1278150Y-142362D03*
X-1212008D03*
G54D44*
X-341929D03*
X-408071D03*
G54D40*
X-1141240Y-63622D03*
Y-24252D03*
X-1128760Y-83307D03*
X-1118917Y-4567D03*
X-1107500Y-83307D03*
X-1085138D03*
Y-43937D03*
Y-4567D03*
X-806854Y-99635D03*
X-785200D03*
G54D42*
X-806854Y-83100D03*
X-785200D03*
G54D46*
X-224213Y-126220D03*
G54D47*
X-262008D03*
G54D37*
X-1410000Y0D03*
X0Y-136453D03*
X0Y0D03*
G54D38*
X-486810Y-118937D03*
X-181534Y-167165D03*
G54D45*
Y-118937D03*
%LPD*%
G75*
G54D10*
X-1656000Y-135000D03*
X-1633000Y-135500D03*
X-1615000Y-37500D03*
Y-27500D03*
Y-32500D03*
X-1610000Y-37500D03*
Y-32500D03*
Y-27500D03*
X-1600000Y-37500D03*
Y-27500D03*
Y-32500D03*
X-1605000Y-37500D03*
Y-32500D03*
Y-27500D03*
X-1595000Y-37500D03*
Y-32500D03*
Y-27500D03*
X-1580000Y-42500D03*
Y-47500D03*
X-1585000Y-42500D03*
Y-47500D03*
X-1590000D03*
Y-42500D03*
X-1580000Y-27500D03*
Y-32500D03*
Y-37500D03*
X-1585000Y-32500D03*
Y-27500D03*
Y-37500D03*
X-1590000D03*
Y-32500D03*
Y-27500D03*
X-1565000Y-42500D03*
Y-47500D03*
X-1575000Y-42500D03*
Y-47500D03*
X-1570000Y-42500D03*
Y-47500D03*
X-1565000Y-27500D03*
Y-32500D03*
Y-37500D03*
X-1575000Y-27500D03*
Y-32500D03*
Y-37500D03*
X-1570000Y-32500D03*
Y-27500D03*
Y-37500D03*
X-1555000Y-47500D03*
Y-42500D03*
X-1550000Y-47500D03*
Y-42500D03*
X-1560000D03*
Y-47500D03*
X-1545000D03*
Y-42500D03*
Y-37500D03*
Y-32500D03*
Y-27500D03*
X-1555000Y-37500D03*
Y-32500D03*
Y-27500D03*
X-1550000Y-37500D03*
Y-32500D03*
Y-27500D03*
X-1560000D03*
Y-32500D03*
Y-37500D03*
X-1535000Y-42500D03*
Y-47500D03*
X-1540000Y-42500D03*
Y-47500D03*
Y-37500D03*
Y-32500D03*
X-1535000Y-37500D03*
Y-32500D03*
X-1524359Y-125359D03*
X-1497043Y-169390D03*
Y-164390D03*
X-1486693Y-166890D03*
X-1497043Y-149390D03*
X-1486693Y-161890D03*
X-1491652Y-151849D03*
X-1491693Y-156890D03*
X-1497043Y-144390D03*
X-1491693Y-136890D03*
X-1486693Y-141890D03*
Y-146890D03*
X-1497043Y-124390D03*
Y-129390D03*
X-1486693Y-121890D03*
Y-126890D03*
X-1491693Y-131890D03*
X-1497043Y-109390D03*
Y-104390D03*
X-1486693Y-101890D03*
Y-106890D03*
X-1491693Y-111890D03*
Y-116890D03*
X-1497043Y-89390D03*
X-1486693Y-86890D03*
X-1491693Y-91890D03*
Y-96890D03*
X-1486693Y-76890D03*
X-1491693D03*
X-1486693Y-81890D03*
X-1466693Y-166890D03*
X-1476693D03*
Y-161890D03*
X-1481693Y-156890D03*
Y-151890D03*
X-1471693D03*
Y-156890D03*
X-1466693Y-161890D03*
X-1481693Y-136890D03*
X-1471693D03*
X-1466693Y-141890D03*
X-1476693D03*
X-1466693Y-146890D03*
X-1476693D03*
X-1481693Y-131890D03*
X-1466693Y-121890D03*
X-1476693D03*
X-1466693Y-126890D03*
X-1476693D03*
X-1471693Y-131890D03*
X-1481693Y-111890D03*
Y-116890D03*
X-1466693Y-101890D03*
X-1476693D03*
X-1466693Y-106890D03*
X-1476693D03*
X-1471693Y-111890D03*
Y-116890D03*
X-1481693Y-91890D03*
Y-96890D03*
X-1466693Y-86890D03*
X-1476693D03*
X-1471693Y-91890D03*
Y-96890D03*
X-1476693Y-81890D03*
X-1461693Y-151890D03*
Y-156890D03*
Y-136890D03*
Y-131890D03*
Y-111890D03*
Y-116890D03*
Y-91890D03*
Y-96890D03*
X-1450000Y-175000D03*
X-1437500Y-162500D03*
X-1450000Y-150000D03*
Y-125000D03*
X-1443500Y-94000D03*
X-1450000Y-100000D03*
X-1434892Y-40389D03*
Y-50389D03*
Y-45389D03*
Y-35389D03*
X-1425000Y-175000D03*
X-1424500Y-100000D03*
X-1425000Y-87500D03*
Y-62500D03*
X-1419892Y-50389D03*
Y-40389D03*
Y-45389D03*
X-1427392Y-50389D03*
Y-45389D03*
Y-40389D03*
X-1419892Y-35389D03*
X-1427392D03*
X-1432000Y-18000D03*
X-1412500Y-162500D03*
X-1412000Y-87000D03*
X-1412500Y-75000D03*
X-1404892Y-50389D03*
Y-45389D03*
Y-40389D03*
X-1412392Y-50389D03*
Y-45389D03*
Y-40389D03*
X-1404892Y-35389D03*
X-1412392D03*
X-1407000Y-18000D03*
X-1407500Y14500D03*
X-1400000Y-175000D03*
X-1387500Y-162500D03*
X-1400000Y-150000D03*
X-1387500Y-137500D03*
X-1400000Y-125000D03*
X-1387500Y-112500D03*
X-1400500Y-87000D03*
X-1391000Y-96500D03*
X-1387500Y-75000D03*
X-1400000Y-62500D03*
X-1389892Y-40389D03*
Y-45389D03*
Y-50389D03*
X-1397392Y-40389D03*
Y-45389D03*
Y-50389D03*
X-1389892Y-35389D03*
X-1397392D03*
X-1395000Y-8000D03*
X-1375000Y-62500D03*
X-1382392Y-40389D03*
Y-45389D03*
Y-50389D03*
Y-35389D03*
X-1382500Y-18000D03*
Y-500D03*
Y14500D03*
X-1362500Y-75000D03*
X-1370000Y-8000D03*
X-1357500Y-500D03*
X-1370000Y7000D03*
X-1357500Y14500D03*
X-1350000Y-62500D03*
X-1345000Y-8000D03*
Y7000D03*
X-1335400Y-75000D03*
Y-37600D03*
X-1332500Y-500D03*
Y14500D03*
X-1322228Y-88400D03*
X-1316728Y-89200D03*
X-1320000Y7000D03*
X-1293500Y-80000D03*
X-1307500Y14500D03*
X-1282500D03*
X-1271813Y-181337D03*
X-1264267Y-181074D03*
X-1271813Y-185937D03*
X-1264013D03*
X-1263189Y-177998D03*
X-1272638D03*
X-1274213Y-157350D03*
X-1264764D03*
X-1265588Y-154080D03*
X-1273388D03*
Y-149480D03*
X-1265588D03*
X-1263925Y-146735D03*
X-1264060Y-141950D03*
X-1248010Y-184405D03*
Y-192205D03*
X-1253740Y-177998D03*
X-1255315Y-157350D03*
X-1256125Y-146735D03*
Y-142135D03*
X-1257500Y-45000D03*
Y-20000D03*
Y14500D03*
X-1230040Y-183080D03*
Y-187680D03*
X-1237840Y-183080D03*
Y-187680D03*
X-1243410Y-184405D03*
Y-192205D03*
X-1234843Y-177998D03*
X-1236418Y-157350D03*
X-1235593Y-136650D03*
Y-132050D03*
X-1232500Y-20000D03*
Y14500D03*
X-1215945Y-177998D03*
X-1225394D03*
X-1217520Y-157350D03*
X-1226969D03*
X-1218290Y-152200D03*
X-1226090D03*
X-1218290Y-147600D03*
X-1226090D03*
X-1227793Y-136650D03*
Y-132050D03*
X-1211720Y-169660D03*
Y-165060D03*
X-1203920D03*
Y-169660D03*
X-1199500Y-3000D03*
X-1207500Y14500D03*
X-1182500D03*
X-1151500Y-15000D03*
X-1157500Y14500D03*
X-1137500Y-15000D03*
X-1126000Y-2500D03*
X-1132500Y14500D03*
X-1111500Y-15000D03*
X-1107500Y14500D03*
X-1100000Y-2500D03*
X-1082500Y14500D03*
X-1070000D03*
X-1045000D03*
X-1015729Y-100550D03*
X-1012638Y-85886D03*
X-1015179Y-74100D03*
X-1012638Y-70873D03*
Y-56060D03*
X-1012860Y-41250D03*
X-1020000Y14500D03*
X-1003380Y-86986D03*
X-1008429Y-91400D03*
X-999960Y-90706D03*
X-996670Y-75460D03*
X-1008719Y-75998D03*
X-999860Y-75848D03*
Y-60885D03*
X-1003780Y-56060D03*
X-994280Y-40890D03*
X-997500Y-7500D03*
X-995000Y14500D03*
X-969331Y-100849D03*
Y-85886D03*
X-965512Y-90706D03*
X-971779Y-73800D03*
X-965412Y-75848D03*
Y-45922D03*
X-970000Y-7500D03*
Y14500D03*
X-956653Y-90706D03*
X-960273Y-101049D03*
X-953250Y-75340D03*
X-956553Y-75848D03*
X-957779Y-57700D03*
X-956553Y-60885D03*
Y-45922D03*
X-945000Y-7500D03*
Y14500D03*
X-922500Y-159500D03*
Y-132500D03*
Y-107500D03*
Y-82500D03*
Y-57500D03*
Y-7500D03*
X-922000Y14500D03*
X-910000Y-170000D03*
Y-95000D03*
Y-70000D03*
Y-45000D03*
Y-20000D03*
Y5000D03*
X-885000Y-170000D03*
X-897500Y-159500D03*
Y-132500D03*
Y-107500D03*
X-885000Y-95000D03*
X-897500Y-82500D03*
X-885000Y-70000D03*
X-897500Y-57500D03*
X-885000Y-45000D03*
Y-20000D03*
X-897500Y-7500D03*
X-885000Y5000D03*
X-897500Y14500D03*
X-872500Y-159500D03*
Y-132500D03*
Y-107500D03*
Y-82500D03*
Y-57500D03*
Y-7500D03*
Y14500D03*
X-860000Y-170000D03*
Y-95000D03*
Y-70000D03*
Y-45000D03*
Y-20000D03*
Y5000D03*
X-847500Y-159500D03*
Y-132500D03*
Y-107500D03*
Y-82500D03*
Y-57500D03*
Y-7500D03*
X-848000Y14500D03*
X-822500Y-159500D03*
Y-132500D03*
X-835000Y-120000D03*
X-822500Y-107500D03*
X-835000Y-95000D03*
X-822500Y-82500D03*
X-835000Y-70000D03*
X-822500Y-57500D03*
X-835000Y-45000D03*
X-822500Y-7500D03*
X-835000Y-20000D03*
X-822500Y14500D03*
X-810000Y-20000D03*
Y5000D03*
X-797500Y-7500D03*
Y14500D03*
X-785000Y-20000D03*
Y5000D03*
X-772500Y-132500D03*
Y-107500D03*
Y-82500D03*
Y-57500D03*
X-760000Y-45000D03*
Y-20000D03*
X-772500Y-7500D03*
X-760000Y5000D03*
X-772500Y14500D03*
X-747500Y-7500D03*
Y14500D03*
X-735000Y-45000D03*
Y-20000D03*
Y5000D03*
X-722500Y-7500D03*
Y14500D03*
X-710000Y-45000D03*
X-697500Y-7500D03*
X-710000Y-20000D03*
Y5000D03*
X-697500Y14500D03*
X-685000Y-45000D03*
Y-20000D03*
Y5000D03*
X-672500Y-7500D03*
Y14500D03*
X-655500Y-25500D03*
X-643700Y-125400D03*
X-642500Y-25500D03*
Y-37500D03*
Y-12500D03*
X-645000Y14500D03*
X-626964Y-169390D03*
Y-164390D03*
X-616614Y-166890D03*
X-621614Y-156890D03*
X-621573Y-151849D03*
X-616614Y-161890D03*
X-627200Y-151300D03*
X-621614Y-136890D03*
X-616614Y-146890D03*
Y-141890D03*
X-626900Y-141300D03*
X-621614Y-131890D03*
X-616614Y-126890D03*
Y-121890D03*
X-621614D03*
X-628700Y-130100D03*
X-621614Y-116890D03*
Y-111890D03*
X-626964Y-104390D03*
Y-109390D03*
X-616614Y-106890D03*
Y-101890D03*
X-621614Y-96890D03*
Y-91890D03*
X-626964Y-89390D03*
X-616614Y-86890D03*
Y-76890D03*
X-621614D03*
X-616614Y-81890D03*
X-626625Y-81614D03*
X-626614Y-76890D03*
Y-71890D03*
X-621614D03*
X-616614D03*
X-630000Y-37500D03*
X-616000Y-25500D03*
X-606614Y-166890D03*
X-601614Y-156890D03*
Y-151890D03*
X-611614D03*
Y-156890D03*
X-606614Y-161890D03*
Y-146890D03*
Y-141890D03*
X-601614Y-136890D03*
X-611614D03*
X-601614Y-131890D03*
X-606614Y-126890D03*
Y-121890D03*
X-611614Y-131890D03*
X-601614Y-116890D03*
Y-111890D03*
X-606614Y-106890D03*
Y-101890D03*
X-611614Y-116890D03*
Y-111890D03*
X-601614Y-96890D03*
Y-91890D03*
X-606614Y-86890D03*
X-611614Y-96890D03*
Y-91890D03*
X-606614Y-81890D03*
X-602500Y-25000D03*
Y0D03*
X-596614Y-166890D03*
X-591614Y-156890D03*
Y-151890D03*
X-596614Y-161890D03*
X-591614Y-136890D03*
X-596614Y-146890D03*
Y-141890D03*
X-591614Y-131890D03*
X-596614Y-126890D03*
Y-121890D03*
X-591614Y-116890D03*
Y-111890D03*
X-596614Y-106890D03*
Y-101890D03*
X-591614Y-96890D03*
Y-91890D03*
X-596614Y-86890D03*
X-590000Y-37500D03*
Y-12500D03*
Y12500D03*
X-577500Y-165000D03*
Y-140000D03*
Y-115000D03*
Y-65000D03*
Y-25000D03*
Y0D03*
X-565000Y-177500D03*
Y-152500D03*
Y-37500D03*
Y-12500D03*
Y12500D03*
X-540000Y-177500D03*
X-552500Y-165000D03*
X-540000Y-152500D03*
X-552500Y-140000D03*
X-540000Y-127500D03*
Y-102500D03*
Y-77500D03*
X-552500Y-65000D03*
Y-25000D03*
X-540000Y-37500D03*
Y-12500D03*
X-552500Y0D03*
X-540000Y12500D03*
X-527500Y-165000D03*
Y-140000D03*
Y-115000D03*
Y-90000D03*
Y-65000D03*
Y-25000D03*
Y0D03*
X-515000Y-177500D03*
Y-152500D03*
Y-127500D03*
Y-102500D03*
Y-77500D03*
Y-37500D03*
Y-12500D03*
Y12500D03*
X-490000Y-102500D03*
X-502500Y-90000D03*
X-490000Y-77500D03*
X-502500Y-65000D03*
X-490000Y-37500D03*
X-502500Y-25000D03*
X-490000Y-12500D03*
X-502500Y0D03*
X-490000Y12500D03*
X-477500Y-25000D03*
Y0D03*
X-462000Y-73500D03*
X-465000Y-37500D03*
Y12500D03*
X-453628Y-88300D03*
X-448128Y-88800D03*
X-449000Y6500D03*
X-431000D03*
X-440000Y12500D03*
X-424500Y-26500D03*
X-413500Y12500D03*
X-401735Y-181337D03*
Y-185937D03*
X-402559Y-177998D03*
X-403309Y-149480D03*
Y-154080D03*
X-395509Y-149480D03*
Y-154080D03*
X-404134Y-157350D03*
X-402500Y12500D03*
X-394188Y-181074D03*
X-393935Y-185937D03*
X-383661Y-177998D03*
X-393110D03*
X-385237Y-157350D03*
X-394685D03*
X-393847Y-146735D03*
X-393981Y-141950D03*
X-386047Y-142135D03*
Y-146735D03*
X-386500Y-56500D03*
Y-44000D03*
Y-31500D03*
Y-19000D03*
Y-5500D03*
X-390000Y12500D03*
X-367761Y-183080D03*
Y-187680D03*
X-377931Y-184405D03*
Y-192205D03*
X-373331D03*
Y-184405D03*
X-364764Y-177998D03*
X-366339Y-157350D03*
X-365514Y-136650D03*
Y-132050D03*
X-374000Y-56500D03*
Y-44000D03*
Y-31500D03*
Y-19000D03*
X-365000Y12500D03*
X-377500D03*
X-359961Y-183080D03*
Y-187680D03*
X-355315Y-177998D03*
X-347441Y-157350D03*
X-356011Y-152200D03*
X-348211D03*
X-356890Y-157350D03*
X-357714Y-136650D03*
X-356011Y-147600D03*
X-348211D03*
X-357714Y-132050D03*
X-360500Y-87100D03*
X-353700Y-87600D03*
X-361500Y-56500D03*
X-348000Y-57000D03*
X-361500Y-44000D03*
X-348000D03*
Y-31500D03*
X-361500D03*
Y-19000D03*
X-348000D03*
X-352500Y12500D03*
X-341641Y-169660D03*
Y-165060D03*
X-333841D03*
Y-169660D03*
X-345866Y-177998D03*
X-347850Y-87050D03*
X-342400Y-87500D03*
X-336000Y-53000D03*
Y-28000D03*
Y-15500D03*
X-340000Y12500D03*
X-323500Y-65500D03*
X-327500Y12500D03*
X-315000D03*
X-302500D03*
X-285000Y-107400D03*
Y-103100D03*
X-290000Y12500D03*
X-277500D03*
X-254800Y-170650D03*
X-254800Y-175150D03*
X-255672Y-157483D03*
Y-152883D03*
X-256496Y-147990D03*
Y-136730D03*
X-254721Y-129000D03*
X-258732Y-104171D03*
X-255500Y-25500D03*
X-268000Y-13000D03*
X-255500D03*
Y-500D03*
X-268000D03*
X-265000Y12500D03*
X-247872Y-152883D03*
Y-157483D03*
X-247047Y-148090D03*
Y-136730D03*
X-240924Y-123960D03*
X-250321Y-129000D03*
X-240924Y-116160D03*
X-243000Y-40500D03*
Y-25500D03*
Y-13000D03*
Y-500D03*
X-240000Y12500D03*
X-252500D03*
X-226200Y-170650D03*
X-226121Y-175150D03*
X-237598Y-136730D03*
X-228150D03*
Y-148090D03*
X-237598D03*
X-236324Y-123960D03*
Y-116160D03*
X-228932Y-104183D03*
X-230000Y-13500D03*
X-230500Y-500D03*
X-227500Y12500D03*
X-215000D03*
X-202500D03*
X-177500D03*
X-190390Y12740D03*
X-165000Y12500D03*
X-145650Y-100550D03*
X-145100Y-74100D03*
X-152500Y12500D03*
X-138440Y-91390D03*
X-133301Y-86986D03*
X-142559Y-85886D03*
X-129882Y-90706D03*
X-129782Y-75998D03*
X-138640D03*
X-142559Y-70873D03*
X-133701Y-56060D03*
X-129782Y-60885D03*
X-142559Y-56060D03*
X-142130Y-41290D03*
X-139000Y-8500D03*
Y-21000D03*
X-140000Y12500D03*
X-127500D03*
X-126600Y-75410D03*
X-124590Y-41500D03*
X-114000Y-33500D03*
X-126500Y-21000D03*
X-114000Y-8500D03*
Y-21000D03*
X-126500Y-8500D03*
X-115000Y12500D03*
X-99252Y-100849D03*
Y-85886D03*
X-101700Y-73800D03*
X-101500Y-33500D03*
Y-21000D03*
Y-8500D03*
X-102500Y12500D03*
X-95433Y-90706D03*
X-86575D03*
X-90194Y-101049D03*
X-83310Y-75360D03*
X-95333Y-75848D03*
X-86475D03*
Y-60885D03*
X-87700Y-57700D03*
X-95333Y-45922D03*
X-86475D03*
X-89000Y-8500D03*
Y-21000D03*
X-90000Y12500D03*
X-74921Y-171500D03*
X-71500Y-158500D03*
Y-146000D03*
Y-133500D03*
X-71700Y-121000D03*
X-70500Y-108600D03*
X-76500Y-33500D03*
Y-21000D03*
Y-8500D03*
X-77500Y12500D03*
X-65000D03*
X-59500Y-173500D03*
Y-161000D03*
Y-136000D03*
Y-148500D03*
Y-123500D03*
Y-108500D03*
Y-96000D03*
Y-83500D03*
Y-71000D03*
Y-58500D03*
Y-46000D03*
Y-33500D03*
Y-8500D03*
Y-21000D03*
X-54500Y1500D03*
X-52500Y12500D03*
X-42500Y-173500D03*
X-43000Y-158500D03*
Y-146000D03*
X-47000Y-71000D03*
X-34500Y-83500D03*
Y-71000D03*
X-47000Y-83500D03*
X-34500Y-58500D03*
X-47000D03*
Y-46000D03*
X-34500D03*
Y-33500D03*
X-47000D03*
Y-21000D03*
X-34500Y-8500D03*
X-47000D03*
X-34500Y-21000D03*
X-42000Y1500D03*
X-40000Y12500D03*
X-18000Y-173500D03*
Y-158500D03*
X-30500D03*
Y-146000D03*
X-18000D03*
X-21150Y-83600D03*
X-22000Y-71000D03*
Y-58500D03*
Y-46000D03*
Y-33500D03*
Y-21000D03*
Y-8500D03*
X-27500Y12500D03*
X-9500Y-120000D03*
Y-108500D03*
Y-96000D03*
X-9350Y-83500D03*
X-9500Y-71000D03*
Y-58500D03*
Y-46000D03*
Y-33500D03*
Y-8500D03*
Y-21000D03*
X-17000Y1500D03*
X-2500Y12500D03*
X-15000D03*
X3000Y-120000D03*
Y-108500D03*
Y-96000D03*
Y-83500D03*
Y-71000D03*
Y-58500D03*
Y-46000D03*
Y-33500D03*
Y-21000D03*
Y-8500D03*
G54D20*
X-271161Y-132520D03*
Y-112835D03*
Y-94331D03*
X-262008Y-150630D03*
X-243110D03*
X-224213D03*
X-215059Y-132520D03*
Y-112835D03*
Y-94331D03*
G54D11*
X-1649000Y-97878D03*
X-1296260Y-175039D03*
X-1304134D03*
X-1296260Y-167165D03*
X-1304134D03*
X-1296260Y-159291D03*
X-1304134D03*
X-1296260Y-143543D03*
X-1304134D03*
X-1296260Y-135669D03*
X-1304134D03*
X-1296260Y-127795D03*
X-1304134D03*
X-426181Y-175039D03*
X-434055D03*
X-426181Y-167165D03*
X-434055D03*
X-426181Y-159291D03*
X-434055D03*
X-426181Y-143543D03*
X-434055D03*
X-426181Y-135669D03*
X-434055D03*
X-426181Y-127795D03*
X-434055D03*
G54D30*
G01X-1020800Y-457700D02*
G02X-1020300Y-458200I0J-500D01*
G01Y-458400D01*
G02X-1020900Y-459000I-600J0D01*
G01X-1021300D01*
G01X-1021800Y-460500D02*
Y-457700D01*
X-1020600D01*
G01X-1018340Y-459100D02*
G03I-2660J0D01*
G01X-1020700D02*
X-1020200Y-460500D01*
G54D21*
X-181534Y-145000D03*
G54D12*
X-1615984Y-178583D03*
X-1608110Y-167165D03*
X-1615984Y-162047D03*
Y-151024D03*
X-1608110Y-150630D03*
X-1615984Y-140000D03*
Y-145512D03*
X-1608110Y-134094D03*
Y-117559D03*
X-1615984Y-112441D03*
X-1608110Y-112047D03*
Y-106535D03*
Y-101024D03*
X-1615984Y-95906D03*
X-1592362Y-167165D03*
X-1600236Y-178583D03*
X-1592362Y-150630D03*
X-1600236Y-162047D03*
X-1592362Y-134094D03*
X-1600236Y-145512D03*
Y-128976D03*
X-1592362Y-117559D03*
X-1600236Y-112441D03*
X-1592362Y-101024D03*
X-1600236Y-95906D03*
X-1576614Y-167165D03*
X-1584488Y-178583D03*
X-1576614Y-150630D03*
X-1584488Y-162047D03*
X-1576614Y-134094D03*
X-1584488Y-145512D03*
Y-128976D03*
X-1576614Y-117559D03*
Y-101024D03*
X-1584488Y-112441D03*
Y-95906D03*
X-1560866Y-167165D03*
X-1568740Y-178583D03*
X-1560866Y-150630D03*
X-1568740Y-162047D03*
X-1560866Y-134094D03*
X-1568740Y-145512D03*
Y-128976D03*
X-1560866Y-117559D03*
X-1568740Y-112441D03*
X-1560866Y-101024D03*
X-1568740Y-95906D03*
X-1545118Y-167165D03*
X-1552992Y-178583D03*
X-1545118Y-150630D03*
X-1552992Y-162047D03*
X-1545118Y-134094D03*
X-1552992Y-145512D03*
Y-128976D03*
X-1545118Y-117559D03*
X-1552992Y-112441D03*
X-1545118Y-101024D03*
X-1552992Y-95906D03*
X-1189134Y-167559D03*
X-1197008Y-178976D03*
X-1189134Y-151024D03*
X-1197008Y-162441D03*
Y-145906D03*
Y-129370D03*
X-1173386Y-167559D03*
X-1181260Y-178976D03*
Y-162441D03*
Y-129370D03*
X-1157638Y-167559D03*
X-1165512Y-178976D03*
X-1157638Y-151024D03*
X-1165512Y-162441D03*
X-1157638Y-134488D03*
X-1165512Y-145906D03*
Y-129370D03*
X-1014488Y-178976D03*
Y-162441D03*
Y-145906D03*
Y-129370D03*
X-1006614Y-167559D03*
X-998740Y-178976D03*
X-1006614Y-151024D03*
X-998740Y-162441D03*
X-1006614Y-134488D03*
X-998740Y-145906D03*
Y-129370D03*
X-990866Y-167559D03*
X-982992Y-178976D03*
X-990866Y-151024D03*
X-982992Y-162441D03*
X-990866Y-134488D03*
X-982992Y-145906D03*
Y-129370D03*
X-975118Y-167559D03*
Y-151024D03*
Y-134488D03*
X-745906D03*
Y-128976D03*
Y-123465D03*
Y-117953D03*
Y-106929D03*
Y-101417D03*
X-738032Y-167165D03*
X-730157Y-178583D03*
X-738032Y-150630D03*
X-730157Y-162047D03*
X-738032Y-134094D03*
X-730157Y-145512D03*
Y-128976D03*
X-738032Y-117559D03*
X-730157Y-112441D03*
X-738032Y-112047D03*
Y-106535D03*
Y-101024D03*
X-730157Y-95906D03*
X-722283Y-167165D03*
X-714409Y-178583D03*
X-722283Y-150630D03*
X-714409Y-162047D03*
X-722283Y-134094D03*
X-714409Y-145512D03*
X-722283Y-117559D03*
X-714409Y-128976D03*
X-722283Y-101024D03*
X-714409Y-112441D03*
Y-95906D03*
X-706535Y-167165D03*
X-698661Y-178583D03*
X-706535Y-150630D03*
X-698661Y-162047D03*
X-706535Y-134094D03*
X-698661Y-145512D03*
X-706535Y-117559D03*
X-698661Y-128976D03*
X-706535Y-101024D03*
X-698661Y-112441D03*
Y-95906D03*
X-690787Y-167165D03*
X-682913Y-178583D03*
X-690787Y-150630D03*
X-682913Y-162047D03*
X-690787Y-134094D03*
X-682913Y-145512D03*
Y-128976D03*
X-690787Y-117559D03*
Y-101024D03*
X-682913Y-112441D03*
Y-95906D03*
X-675039Y-167165D03*
Y-150630D03*
Y-134094D03*
Y-117559D03*
Y-101024D03*
X-319055Y-167559D03*
X-326929Y-178976D03*
X-319055Y-151024D03*
X-326929Y-162441D03*
Y-145906D03*
Y-129370D03*
X-303307Y-167559D03*
X-311181Y-178976D03*
Y-162441D03*
Y-129370D03*
X-287559Y-167559D03*
X-295433Y-178976D03*
X-287559Y-151024D03*
X-295433Y-162441D03*
X-287559Y-134488D03*
X-295433Y-145906D03*
Y-129370D03*
X-144409Y-178976D03*
Y-162441D03*
Y-145906D03*
Y-129370D03*
X-136535Y-167559D03*
X-128661Y-178976D03*
X-136535Y-151024D03*
X-128661Y-162441D03*
X-136535Y-134488D03*
X-128661Y-145906D03*
Y-129370D03*
X-120787Y-167559D03*
X-112913Y-178976D03*
X-120787Y-151024D03*
X-112913Y-162441D03*
X-120787Y-134488D03*
X-112913Y-145906D03*
Y-129370D03*
X-105039Y-167559D03*
Y-151024D03*
Y-134488D03*
G54D22*
G01X-1184000Y-502500D02*
Y-512500D01*
G01X-1186683Y-502500D02*
X-1181317D01*
G01X-1176833Y-512500D02*
Y-502500D01*
X-1173917D01*
X-1172983Y-503000D01*
X-1172400Y-503667D01*
X-1172167Y-505000D01*
X-1172400Y-506333D01*
X-1173100Y-507167D01*
X-1173917Y-507667D01*
X-1176833D01*
G01X-1173917D02*
X-1172167Y-512500D01*
G01X-1167917D02*
X-1165000Y-502500D01*
X-1162083Y-512500D01*
G01X-1163133Y-509000D02*
X-1166867D01*
G01X-1155500Y-512500D02*
Y-508000D01*
X-1157833Y-502500D01*
G01X-1153167D02*
X-1155500Y-508000D01*
G01X-1135567Y-507167D02*
X-1135100Y-506667D01*
X-1134750Y-505834D01*
X-1134517Y-504667D01*
X-1134750Y-503667D01*
X-1135217Y-503000D01*
X-1136033Y-502500D01*
X-1139183D01*
Y-512500D01*
X-1135333D01*
X-1134517Y-511833D01*
X-1134050Y-510833D01*
X-1133817Y-509667D01*
X-1134050Y-508500D01*
X-1134750Y-507500D01*
X-1135567Y-507167D01*
X-1139183D01*
G01X-1129917Y-512500D02*
X-1127000Y-502500D01*
X-1124083Y-512500D01*
G01X-1125133Y-509000D02*
X-1128867D01*
G01X-1114933Y-503333D02*
X-1115633Y-502833D01*
X-1116450Y-502500D01*
X-1117383D01*
X-1118433Y-503000D01*
X-1119250Y-503833D01*
X-1119833Y-504833D01*
X-1120300Y-506500D01*
X-1120417Y-508000D01*
X-1120183Y-509500D01*
X-1119833Y-510500D01*
X-1119133Y-511500D01*
X-1118317Y-512167D01*
X-1117500Y-512500D01*
X-1116683D01*
X-1115867Y-512167D01*
X-1115167Y-511667D01*
X-1114583Y-511000D01*
G01X-1110567Y-512500D02*
Y-502500D01*
G01X-1106133D02*
X-1110567Y-508667D01*
G01X-1105433Y-512500D02*
X-1108583Y-505834D01*
G01X-1100833Y-512500D02*
Y-502500D01*
X-1098033D01*
X-1097100Y-503000D01*
X-1096400Y-504167D01*
X-1096167Y-505500D01*
X-1096400Y-506833D01*
X-1096983Y-507833D01*
X-1098033Y-508334D01*
X-1100833D01*
G01X-1091333Y-502500D02*
Y-512500D01*
X-1086667D01*
G01X-1082417D02*
X-1079500Y-502500D01*
X-1076583Y-512500D01*
G01X-1077633Y-509000D02*
X-1081367D01*
G01X-1072683Y-512500D02*
Y-502500D01*
X-1067317Y-512500D01*
Y-502500D01*
G01X-1058167Y-512500D02*
X-1062833D01*
Y-502500D01*
X-1058167D01*
G01X-1060033Y-507333D02*
X-1062833D01*
G01X-1043717Y-512500D02*
Y-502500D01*
X-1039283D01*
G01X-1040917Y-507333D02*
X-1043717D01*
G01X-1034917Y-512500D02*
X-1032000Y-502500D01*
X-1029083Y-512500D01*
G01X-1030133Y-509000D02*
X-1033867D01*
G01X-1021567Y-507167D02*
X-1021100Y-506667D01*
X-1020750Y-505834D01*
X-1020517Y-504667D01*
X-1020750Y-503667D01*
X-1021217Y-503000D01*
X-1022033Y-502500D01*
X-1025183D01*
Y-512500D01*
X-1021333D01*
X-1020517Y-511833D01*
X-1020050Y-510833D01*
X-1019817Y-509667D01*
X-1020050Y-508500D01*
X-1020750Y-507500D01*
X-1021567Y-507167D01*
X-1025183D01*
G01X-1002567D02*
X-1002100Y-506667D01*
X-1001750Y-505834D01*
X-1001517Y-504667D01*
X-1001750Y-503667D01*
X-1002217Y-503000D01*
X-1003033Y-502500D01*
X-1006183D01*
Y-512500D01*
X-1002333D01*
X-1001517Y-511833D01*
X-1001050Y-510833D01*
X-1000817Y-509667D01*
X-1001050Y-508500D01*
X-1001750Y-507500D01*
X-1002567Y-507167D01*
X-1006183D01*
G01X-985083Y-515833D02*
X-986250Y-514167D01*
X-986833Y-512500D01*
Y-505834D01*
X-986250Y-504167D01*
X-985083Y-502500D01*
G01X-975000Y-512500D02*
X-975933Y-512333D01*
X-976750Y-511667D01*
X-977450Y-510667D01*
X-977917Y-509500D01*
X-978150Y-508167D01*
Y-506833D01*
X-977917Y-505500D01*
X-977450Y-504333D01*
X-976750Y-503333D01*
X-975933Y-502667D01*
X-975000Y-502500D01*
X-974067Y-502667D01*
X-973250Y-503333D01*
X-972550Y-504333D01*
X-972083Y-505500D01*
X-971850Y-506833D01*
Y-508167D01*
X-972083Y-509500D01*
X-972550Y-510667D01*
X-973250Y-511667D01*
X-974067Y-512333D01*
X-975000Y-512500D01*
G01X-967950Y-511167D02*
X-967017Y-512000D01*
X-965967Y-512500D01*
X-965033D01*
X-964100Y-512000D01*
X-963400Y-511167D01*
X-963050Y-510000D01*
X-963283Y-508834D01*
X-963867Y-507833D01*
X-964917Y-507167D01*
X-966317Y-506833D01*
X-967133Y-506167D01*
X-967483Y-505000D01*
X-967250Y-503833D01*
X-966667Y-503000D01*
X-965850Y-502500D01*
X-965033D01*
X-964217Y-502833D01*
X-963517Y-503667D01*
G01X-958333Y-512500D02*
Y-502500D01*
X-955533D01*
X-954600Y-503000D01*
X-953900Y-504167D01*
X-953667Y-505500D01*
X-953900Y-506833D01*
X-954483Y-507833D01*
X-955533Y-508334D01*
X-958333D01*
G01X-945917Y-515833D02*
X-944750Y-514167D01*
X-944167Y-512500D01*
Y-505834D01*
X-944750Y-504167D01*
X-945917Y-502500D01*
G01X-902000Y-470000D02*
Y-460000D01*
X-903400Y-462000D01*
G01Y-470000D02*
X-900600D01*
G01X-892500Y-470333D02*
X-892733Y-470167D01*
Y-469833D01*
X-892500Y-469667D01*
X-892267Y-469833D01*
Y-470167D01*
X-892500Y-470333D01*
G01Y-465834D02*
X-892733Y-465667D01*
Y-465333D01*
X-892500Y-465167D01*
X-892267Y-465333D01*
Y-465667D01*
X-892500Y-465834D01*
G01X-883000Y-470000D02*
Y-460000D01*
X-884400Y-462000D01*
G01Y-470000D02*
X-881600D01*
G01X-785060Y-472187D02*
X-784127Y-473020D01*
X-783077Y-473520D01*
X-782143D01*
X-781210Y-473020D01*
X-780510Y-472187D01*
X-780160Y-471020D01*
X-780393Y-469854D01*
X-780977Y-468853D01*
X-782027Y-468187D01*
X-783427Y-467853D01*
X-784243Y-467187D01*
X-784593Y-466020D01*
X-784360Y-464853D01*
X-783777Y-464020D01*
X-782960Y-463520D01*
X-782143D01*
X-781327Y-463853D01*
X-780627Y-464687D01*
G01X-775560Y-473520D02*
Y-463520D01*
G01X-770660D02*
Y-473520D01*
G01Y-468520D02*
X-775560D01*
G01X-766527Y-473520D02*
X-763610Y-463520D01*
X-760693Y-473520D01*
G01X-761743Y-470020D02*
X-765477D01*
G01X-757610Y-463520D02*
X-755977Y-473520D01*
X-754110Y-463520D01*
X-752243Y-473520D01*
X-750610Y-463520D01*
G01X-668067Y-470500D02*
X-667367Y-471667D01*
X-666433Y-472333D01*
X-665383Y-472500D01*
X-664450Y-472333D01*
X-663517Y-471500D01*
X-662933Y-470500D01*
X-662817Y-469500D01*
X-663050Y-468334D01*
X-663867Y-467500D01*
X-664683Y-467167D01*
X-665733D01*
G01X-664683D02*
X-663983Y-466667D01*
X-663400Y-465834D01*
X-663167Y-464833D01*
X-663400Y-463833D01*
X-663983Y-463000D01*
X-665033Y-462500D01*
X-666083Y-462667D01*
X-667133Y-463333D01*
G01X-656000Y-462500D02*
X-656933Y-462833D01*
X-657633Y-463667D01*
X-658100Y-464667D01*
X-658450Y-466000D01*
X-658567Y-467500D01*
X-658450Y-469000D01*
X-658100Y-470333D01*
X-657633Y-471334D01*
X-656933Y-472167D01*
X-656000Y-472500D01*
X-655067Y-472167D01*
X-654367Y-471334D01*
X-653900Y-470333D01*
X-653550Y-469000D01*
X-653433Y-467500D01*
X-653550Y-466000D01*
X-653900Y-464667D01*
X-654367Y-463667D01*
X-655067Y-462833D01*
X-656000Y-462500D01*
G01X-648017Y-469167D02*
X-644983D01*
G01X-639917Y-472500D02*
X-637000Y-462500D01*
X-634083Y-472500D01*
G01X-635133Y-469000D02*
X-638867D01*
G01X-629833Y-472500D02*
Y-462500D01*
X-627033D01*
X-626100Y-463000D01*
X-625400Y-464167D01*
X-625167Y-465500D01*
X-625400Y-466833D01*
X-625983Y-467833D01*
X-627033Y-468334D01*
X-629833D01*
G01X-620333Y-472500D02*
Y-462500D01*
X-617417D01*
X-616483Y-463000D01*
X-615900Y-463667D01*
X-615667Y-465000D01*
X-615900Y-466333D01*
X-616600Y-467167D01*
X-617417Y-467667D01*
X-620333D01*
G01X-617417D02*
X-615667Y-472500D01*
G01X-610017Y-469167D02*
X-606983D01*
G01X-599000Y-472500D02*
Y-462500D01*
X-600400Y-464500D01*
G01Y-472500D02*
X-597600D01*
G01X-588100D02*
Y-462500D01*
X-592417Y-469667D01*
X-586583D01*
G54D13*
X-1522728Y-154950D03*
X-652638D03*
X-177597Y-78740D03*
X6890Y-167953D03*
G54D23*
G01X-1174900Y-473500D02*
X-1171300Y-466100D01*
X-1171800Y-465700D01*
X-1175900Y-473200D01*
X-1176200Y-471200D01*
X-1172500Y-465400D01*
X-1175700Y-471300D01*
X-1176500Y-469800D01*
X-1172900Y-464900D01*
X-1173600Y-451800D01*
X-1173700Y-449900D01*
X-1182100D01*
X-1187400Y-473000D01*
X-1182400D01*
X-1177800Y-456000D01*
X-1177000Y-455900D01*
X-1176100Y-468500D01*
X-1173700Y-464500D01*
X-1174600Y-450800D01*
X-1181500Y-450900D01*
X-1186400Y-472100D01*
X-1183100D01*
X-1178300Y-454800D01*
X-1176600Y-455000D01*
X-1175500Y-466300D01*
X-1174600Y-464300D01*
X-1175400Y-451700D01*
X-1181000Y-451800D01*
X-1185300Y-471300D01*
X-1183800Y-471400D01*
X-1179000Y-454300D01*
X-1176200D01*
X-1175200Y-462200D01*
X-1176200Y-452500D01*
X-1180500Y-452800D01*
X-1184300Y-470600D01*
X-1179700Y-453400D01*
X-1176800D01*
G01X-1182820Y-448900D02*
X-1188360Y-473900D01*
X-1181580D01*
X-1177300Y-456700D01*
X-1176920Y-473900D01*
X-1172260D01*
X-1163400Y-456920D01*
X-1167240Y-473900D01*
X-1160380D01*
X-1154840Y-448900D01*
X-1164540D01*
X-1172540Y-464820D01*
X-1172880Y-448900D01*
X-1182820D01*
G01X-1155800Y-449500D02*
X-1161100Y-472900D01*
X-1166100Y-473000D01*
X-1166000Y-471900D01*
X-1161800Y-472100D01*
X-1161300Y-471000D01*
X-1165900Y-471100D01*
X-1165700Y-470000D01*
X-1161300D01*
X-1160800Y-469200D01*
X-1165300Y-469100D01*
X-1165200Y-468100D01*
X-1160700D01*
X-1160400Y-467100D01*
X-1165100Y-467200D01*
X-1164900Y-466300D01*
X-1160300Y-466200D01*
X-1160000Y-465200D01*
X-1164700Y-465300D01*
X-1164400Y-464200D01*
X-1159700Y-464300D01*
X-1159300Y-463100D01*
X-1164700Y-463500D01*
X-1164000Y-462500D01*
X-1159500Y-462600D01*
X-1159000Y-461700D01*
X-1163900D01*
X-1163600Y-460600D01*
X-1159100Y-460800D01*
X-1158800Y-459900D01*
X-1163200D01*
X-1163100Y-459200D01*
X-1158800D01*
X-1158300Y-458500D01*
X-1163000Y-458400D01*
X-1162900Y-457800D01*
X-1158400Y-457900D01*
X-1158200Y-457200D01*
X-1162500Y-457000D01*
X-1163100Y-456500D01*
X-1157800D01*
X-1157500Y-455500D01*
X-1156600Y-449800D01*
X-1164000D01*
X-1164500Y-450700D01*
X-1157600D01*
X-1157800Y-451700D01*
X-1165000Y-451600D01*
X-1165400Y-452400D01*
X-1157900Y-452500D01*
X-1157800Y-453500D01*
X-1165900Y-453200D01*
X-1166200Y-453900D01*
X-1158000Y-454300D01*
X-1158300Y-455300D01*
X-1166600Y-454800D01*
X-1158900Y-455900D01*
X-1167000Y-455600D01*
X-1163500Y-456400D01*
X-1167300Y-456300D01*
X-1171700Y-465200D01*
X-1169200Y-466400D01*
X-1164500Y-457200D01*
X-1166900Y-457100D01*
X-1170600Y-465200D01*
X-1169500Y-465500D01*
X-1166000Y-457800D01*
G01X-1170300Y-466300D02*
X-1174000Y-473600D01*
G01X-1169500Y-466900D02*
X-1172800Y-473000D01*
G01X-1152800Y-456400D02*
X-1156600Y-473100D01*
X-1152200Y-473000D01*
X-1148300Y-456600D01*
X-1149500D01*
X-1152900Y-472000D01*
X-1155600Y-472300D01*
X-1152100Y-456500D01*
X-1150400Y-456400D01*
X-1153600Y-471200D01*
X-1154500Y-471400D01*
X-1151400Y-457200D01*
G01X-1153420Y-455700D02*
X-1157540Y-473900D01*
X-1151380D01*
X-1147440Y-455700D01*
X-1153420D01*
G01X-1151600Y-450100D02*
X-1146700Y-450000D01*
X-1147000Y-451000D01*
X-1151700D01*
G01X-1152020Y-448900D02*
X-1152660Y-451900D01*
X-1146380D01*
X-1145740Y-448900D01*
X-1152020D01*
G01X-1129400Y-468900D02*
X-1131800Y-471900D01*
X-1136500Y-473700D01*
X-1142100Y-473600D01*
X-1144600Y-472300D01*
X-1145800Y-471000D01*
X-1146400Y-469500D01*
X-1146700Y-467600D01*
X-1146500Y-464600D01*
X-1145400Y-461200D01*
X-1143500Y-459100D01*
X-1140200Y-456900D01*
X-1136100Y-456200D01*
X-1132300Y-456400D01*
X-1129400Y-457900D01*
X-1127500Y-460900D01*
X-1132500Y-461000D01*
X-1133400Y-459200D01*
X-1135100Y-458100D01*
X-1136800Y-458000D01*
X-1138600Y-458900D01*
X-1140300Y-460700D01*
X-1141800Y-463600D01*
X-1142400Y-466600D01*
X-1141500Y-470400D01*
X-1140200Y-471500D01*
X-1138300Y-471600D01*
X-1136300Y-471400D01*
X-1134500Y-469100D01*
X-1130300Y-469000D01*
X-1132500Y-471200D01*
X-1134900Y-472000D01*
X-1137200Y-472800D01*
X-1142300Y-472700D01*
X-1144900Y-470600D01*
X-1145800Y-467400D01*
X-1145500Y-465100D01*
X-1144700Y-462000D01*
X-1143300Y-460200D01*
X-1139800Y-457700D01*
X-1135400Y-457000D01*
X-1131300Y-457600D01*
X-1128800Y-460100D01*
X-1132100D01*
X-1134300Y-457900D01*
X-1130100Y-458800D01*
X-1129500Y-459400D01*
X-1132600Y-459000D01*
G01X-1133300Y-461900D02*
Y-461420D01*
X-1133640Y-460240D01*
X-1134300Y-459200D01*
X-1135200Y-458900D01*
X-1136580D01*
X-1138060Y-459820D01*
X-1139360Y-461000D01*
X-1140240Y-462220D01*
X-1140880Y-463920D01*
X-1141300Y-465380D01*
X-1141500Y-467060D01*
Y-468020D01*
X-1141020Y-469220D01*
X-1139780Y-470700D01*
X-1137160D01*
X-1135840Y-469500D01*
X-1134980Y-468200D01*
X-1134940Y-468100D01*
X-1128180D01*
X-1128240Y-468240D01*
X-1128840Y-469340D01*
X-1129020Y-469800D01*
X-1129740Y-470700D01*
X-1130500Y-471460D01*
X-1131660Y-472420D01*
X-1132820Y-473200D01*
X-1133740Y-473740D01*
X-1136380Y-474500D01*
X-1141640D01*
X-1142540Y-474320D01*
X-1144220Y-473760D01*
X-1144900Y-473240D01*
X-1146240Y-471900D01*
X-1146780Y-471180D01*
X-1146940Y-470880D01*
X-1147320Y-469660D01*
X-1147500Y-468640D01*
Y-464780D01*
X-1146940Y-462540D01*
X-1146380Y-461580D01*
X-1145980Y-460780D01*
X-1145420Y-459880D01*
X-1143700Y-458140D01*
X-1142740Y-457380D01*
X-1142000Y-456820D01*
X-1140240Y-456040D01*
X-1139500Y-455660D01*
X-1138800Y-455480D01*
X-1137260Y-455300D01*
X-1134320D01*
X-1132020Y-455500D01*
X-1130940Y-455860D01*
X-1130580Y-456020D01*
X-1129260Y-456780D01*
X-1128940Y-457100D01*
X-1127820Y-458420D01*
X-1127060Y-460300D01*
X-1126900Y-460800D01*
Y-461900D01*
X-1133300D01*
G01X-1137900Y-458000D02*
X-1140300Y-459100D01*
X-1142500Y-460900D01*
X-1143900Y-462600D01*
X-1144800Y-467600D01*
X-1144200Y-470000D01*
X-1141000Y-472300D01*
X-1136400Y-472200D01*
X-1131600Y-469600D01*
X-1135400Y-470400D01*
X-1141100Y-471400D01*
X-1142100Y-470700D01*
X-1142700Y-469000D01*
X-1143100Y-467100D01*
X-1142700Y-464100D01*
X-1140500Y-459900D01*
X-1143400Y-463700D01*
X-1143600Y-465700D01*
X-1143900Y-467700D01*
X-1143000Y-469900D01*
G01X-1113500Y-459200D02*
X-1123500Y-459300D01*
X-1123700Y-460100D01*
X-1114300Y-460000D01*
X-1116500Y-460800D01*
X-1124200Y-461000D01*
X-1124400Y-461900D01*
X-1117600Y-461800D01*
X-1118800Y-462800D01*
X-1124500Y-462700D01*
X-1124600Y-463600D01*
X-1119300Y-463700D01*
X-1120100Y-464800D01*
X-1125000Y-464600D01*
Y-465500D01*
X-1120600Y-465700D01*
X-1120800Y-466700D01*
X-1125300Y-466500D01*
X-1125500Y-467400D01*
X-1121000Y-467600D01*
X-1121200Y-468700D01*
X-1125600Y-468400D01*
X-1125900Y-469100D01*
X-1121500Y-469500D01*
X-1121700Y-470700D01*
X-1126100Y-470000D01*
X-1126200Y-470700D01*
X-1121900Y-471200D01*
X-1122100Y-472000D01*
X-1126300Y-471700D01*
X-1126700Y-472300D01*
X-1122100Y-472700D01*
X-1122200Y-473100D01*
X-1126800Y-473200D01*
G01X-1114060Y-460760D02*
X-1114840Y-460920D01*
X-1115740Y-461140D01*
X-1116880Y-461820D01*
X-1117700Y-462640D01*
X-1118620Y-463340D01*
X-1118840Y-464020D01*
X-1119440Y-464820D01*
X-1119660Y-465480D01*
X-1120060Y-466280D01*
X-1120280Y-466960D01*
X-1120480Y-468360D01*
X-1120680Y-468940D01*
X-1120880Y-469940D01*
X-1121080Y-470540D01*
X-1121700Y-472980D01*
X-1121820Y-473900D01*
X-1127640D01*
X-1126920Y-471060D01*
X-1126720Y-470440D01*
X-1126500Y-468800D01*
X-1126320Y-467860D01*
X-1126120Y-467260D01*
X-1125920Y-466260D01*
X-1125720Y-465660D01*
X-1125300Y-464000D01*
X-1125120Y-462220D01*
X-1124920Y-461660D01*
X-1124720Y-460660D01*
X-1124520Y-460060D01*
X-1123720Y-456800D01*
X-1123580Y-455700D01*
X-1117880D01*
X-1118100Y-456160D01*
Y-458740D01*
X-1116500Y-457160D01*
X-1115780Y-456620D01*
X-1114680Y-456060D01*
X-1113560Y-455680D01*
X-1112460Y-455500D01*
X-1111720D01*
X-1112460Y-458440D01*
X-1114060Y-460760D01*
G01X-1123100Y-456500D02*
X-1118900Y-456600D01*
X-1118800Y-457600D01*
X-1123100Y-457500D01*
X-1123300Y-458500D01*
X-1113100Y-458400D01*
X-1112600Y-456400D01*
X-1116100Y-457600D01*
X-1113500D01*
G01X-1105100Y-471100D02*
X-1104060D01*
X-1103780Y-470820D01*
X-1103200Y-470640D01*
X-1102080Y-469740D01*
X-1100800Y-468240D01*
X-1100380Y-467400D01*
X-1100180Y-467100D01*
X-1099960Y-466660D01*
X-1099540Y-465720D01*
X-1099320Y-465060D01*
X-1099100Y-464180D01*
Y-461220D01*
X-1099360Y-460200D01*
X-1099660Y-459900D01*
X-1100700Y-458640D01*
X-1101220Y-458300D01*
X-1103340D01*
X-1103700Y-458640D01*
X-1105300Y-459840D01*
X-1105760Y-460320D01*
X-1106180Y-460940D01*
X-1107060Y-462020D01*
X-1107260Y-462880D01*
X-1107660Y-463660D01*
X-1108100Y-465000D01*
Y-468640D01*
X-1107620Y-469600D01*
X-1107140Y-470340D01*
X-1105980Y-471100D01*
X-1105100D01*
G01X-1112540Y-460460D02*
X-1110680Y-458140D01*
X-1109940Y-457580D01*
X-1109000Y-456840D01*
X-1108480Y-456660D01*
X-1107940Y-456400D01*
X-1107740Y-456200D01*
X-1107480Y-456060D01*
X-1106880Y-455860D01*
X-1106480Y-455660D01*
X-1105960Y-455480D01*
X-1104600Y-455300D01*
X-1103440Y-455100D01*
X-1100940D01*
X-1098240Y-455480D01*
X-1097720Y-455660D01*
X-1097020Y-456020D01*
X-1096180Y-456640D01*
X-1095620Y-456820D01*
X-1095540Y-456900D01*
X-1094200Y-458440D01*
X-1093660Y-459520D01*
X-1093460Y-460100D01*
X-1093100Y-461020D01*
Y-464400D01*
X-1093420Y-465360D01*
X-1094300Y-465520D01*
X-1094720Y-465740D01*
X-1095320Y-465940D01*
X-1096120Y-466340D01*
X-1096720Y-466540D01*
X-1097100Y-466720D01*
X-1098100Y-466920D01*
X-1098520Y-467140D01*
X-1099160Y-467360D01*
X-1101180Y-468700D01*
X-1094660D01*
X-1095220Y-469800D01*
X-1095560Y-470320D01*
X-1097480Y-472220D01*
X-1099940Y-473740D01*
X-1102580Y-474500D01*
X-1108800D01*
X-1109300Y-474340D01*
X-1111220Y-473560D01*
X-1111720Y-473240D01*
X-1113240Y-471720D01*
X-1113560Y-471240D01*
X-1113760Y-470660D01*
X-1114140Y-469980D01*
X-1114320Y-469120D01*
X-1114500Y-468680D01*
Y-464980D01*
X-1114320Y-464260D01*
X-1114140Y-463720D01*
X-1113940Y-463320D01*
X-1113720Y-462660D01*
X-1113560Y-462000D01*
X-1111880Y-460320D01*
X-1112540Y-460460D01*
G01X-1099300Y-466400D02*
X-1093800Y-464400D01*
X-1093900Y-461100D01*
X-1094800Y-459000D01*
X-1096800Y-457300D01*
X-1100000Y-456100D01*
X-1102800Y-455900D01*
X-1106300Y-456300D01*
X-1109600Y-458100D01*
X-1111400Y-460500D01*
X-1112900Y-462600D01*
X-1113600Y-465600D01*
X-1113500Y-469100D01*
X-1112100Y-471900D01*
X-1109600Y-473300D01*
X-1105700Y-473800D01*
X-1101000Y-473400D01*
X-1098200Y-471800D01*
X-1096600Y-470100D01*
X-1096000Y-469500D01*
X-1100800Y-469700D01*
X-1102300Y-471100D01*
X-1097900Y-470400D01*
X-1100300Y-471800D01*
X-1103200Y-471400D01*
X-1100600Y-472600D01*
X-1103000D01*
X-1103700Y-471900D01*
X-1103400Y-473000D01*
X-1104600Y-471900D01*
X-1106200D01*
X-1104100Y-473100D01*
X-1107200Y-472700D01*
X-1110100Y-472100D01*
X-1111500Y-470900D01*
X-1112600Y-468600D01*
X-1112700Y-466000D01*
X-1112400Y-463700D01*
X-1111400Y-461600D01*
X-1109600Y-459500D01*
X-1108100Y-458200D01*
X-1105900Y-457200D01*
X-1102200Y-456700D01*
X-1099600Y-457300D01*
X-1097000Y-458400D01*
X-1095500Y-459500D01*
X-1094600Y-461900D01*
X-1094500Y-463900D01*
X-1098800Y-465200D01*
X-1098600Y-464000D01*
X-1095100Y-463100D01*
X-1095300Y-462000D01*
X-1098500Y-463000D01*
X-1098600Y-461700D01*
X-1095600Y-461300D01*
X-1095900Y-460200D01*
X-1098400Y-460700D01*
X-1098900Y-459900D01*
X-1096600Y-459400D01*
X-1097100Y-458900D01*
X-1099400Y-459000D01*
X-1098800Y-458500D01*
X-1100600Y-458000D01*
X-1102400Y-457400D01*
X-1104200Y-457500D01*
X-1106200Y-458100D01*
X-1107900Y-459000D01*
X-1110500Y-462200D01*
X-1111800Y-464800D01*
Y-467700D01*
X-1110700Y-470300D01*
X-1108700Y-472000D01*
X-1106600Y-471900D01*
X-1107900Y-470300D01*
X-1108900Y-468700D01*
Y-465500D01*
X-1107900Y-462300D01*
X-1106500Y-459900D01*
X-1104100Y-458200D01*
X-1108000Y-460000D01*
X-1108100Y-461500D01*
X-1108700Y-461200D01*
X-1110300Y-463600D01*
X-1111000Y-466000D01*
X-1110700Y-468100D01*
X-1109500Y-470600D01*
X-1107700Y-471400D01*
X-1109300Y-469100D01*
X-1109800Y-467600D01*
X-1108600Y-462200D01*
X-1110400Y-466800D01*
G01X-1113600Y-460900D02*
X-1112100Y-459000D01*
G01X-1093100Y-469400D02*
X-1087900Y-469700D01*
X-1086500Y-471400D01*
X-1083400Y-472300D01*
X-1081000Y-472000D01*
X-1079300Y-470600D01*
X-1079000Y-468900D01*
X-1079500Y-467700D01*
X-1080300Y-466600D01*
X-1081800Y-466000D01*
X-1083300Y-465500D01*
X-1085300Y-465000D01*
X-1087900Y-464000D01*
X-1089100Y-463200D01*
X-1089800Y-461000D01*
X-1089500Y-459000D01*
X-1088600Y-457700D01*
X-1086500Y-456700D01*
X-1084600Y-456100D01*
X-1081900Y-455900D01*
X-1079900Y-455800D01*
X-1076900Y-456300D01*
X-1075000Y-457000D01*
X-1073700Y-458000D01*
X-1073300Y-459400D01*
X-1077600Y-459500D01*
X-1078100Y-458800D01*
X-1074300Y-458500D01*
X-1074600Y-457800D01*
X-1078200Y-458200D01*
X-1076000Y-457400D01*
X-1079100Y-457700D01*
X-1077100Y-456900D01*
X-1080100Y-457300D01*
X-1079200Y-456600D01*
X-1083100Y-456800D01*
X-1080600Y-457300D01*
X-1083400Y-457700D01*
X-1083600Y-457000D01*
X-1087900Y-458400D01*
X-1084000Y-458100D01*
X-1088600Y-459100D01*
X-1088800Y-461500D01*
X-1087700Y-463600D01*
X-1084400Y-464300D01*
X-1081200Y-465400D01*
X-1078800Y-467300D01*
X-1078300Y-470500D01*
X-1079900Y-472600D01*
X-1083500Y-473300D01*
X-1085600Y-472600D01*
X-1088800Y-470500D01*
X-1092600Y-470200D01*
X-1092100Y-471800D01*
X-1091700Y-471300D01*
X-1089300Y-471500D01*
X-1091300Y-472300D01*
X-1088700Y-471600D01*
X-1084000Y-473500D01*
X-1089100D01*
X-1091000Y-472900D01*
X-1087200Y-472800D01*
X-1082700Y-473700D01*
X-1079000Y-473600D01*
X-1076500Y-472300D01*
X-1074700Y-470600D01*
X-1074300Y-467300D01*
X-1074800Y-465300D01*
X-1078800Y-463600D01*
X-1081600Y-462900D01*
X-1083400Y-462500D01*
X-1084800Y-461500D01*
X-1085000Y-458900D01*
X-1088100Y-459800D01*
X-1087200Y-462700D01*
X-1085000Y-463400D01*
X-1082000Y-464100D01*
X-1079600Y-465100D01*
X-1078200Y-466500D01*
X-1077700Y-468500D01*
X-1077500Y-470100D01*
X-1079200Y-472800D01*
X-1076800Y-471400D01*
X-1075300Y-470000D01*
X-1077300Y-470900D01*
X-1075000Y-468800D01*
X-1075200Y-466100D01*
X-1082700Y-462700D01*
X-1084200Y-462900D01*
X-1086600Y-461800D01*
X-1087200Y-460300D01*
X-1085800Y-459800D01*
X-1086600Y-461000D01*
X-1085300Y-460400D01*
X-1085600Y-461400D01*
X-1076700Y-466500D01*
X-1075900Y-467100D01*
X-1075700Y-468400D01*
X-1076800Y-469500D01*
X-1077800Y-466200D01*
X-1075900Y-468800D01*
G01X-1093780Y-468700D02*
X-1087100D01*
Y-469740D01*
X-1086800Y-470060D01*
X-1086520Y-470600D01*
X-1085820Y-470820D01*
X-1085660Y-471000D01*
X-1085120Y-471260D01*
X-1084400Y-471500D01*
X-1082360D01*
X-1080540Y-470600D01*
X-1080100Y-470140D01*
Y-469780D01*
X-1079840Y-469380D01*
X-1080380Y-467740D01*
X-1081440Y-466940D01*
X-1082560Y-466720D01*
X-1085740Y-465920D01*
X-1086940Y-465520D01*
X-1087600Y-465360D01*
X-1087740Y-465200D01*
X-1088540Y-464800D01*
X-1089140Y-464200D01*
X-1089540Y-464000D01*
X-1089800Y-463740D01*
X-1090000Y-463340D01*
X-1090180Y-463180D01*
X-1090500Y-462200D01*
Y-459800D01*
X-1090320Y-459260D01*
X-1090140Y-458500D01*
X-1090000Y-458260D01*
X-1089000Y-457260D01*
X-1088860Y-456940D01*
X-1085920Y-455480D01*
X-1083620Y-455100D01*
X-1082060Y-454900D01*
X-1080520D01*
X-1078580Y-455100D01*
X-1076240Y-455480D01*
X-1075120Y-455860D01*
X-1074800Y-456020D01*
X-1073680Y-456760D01*
X-1073160Y-457300D01*
X-1072620Y-458020D01*
X-1072500Y-458240D01*
Y-460300D01*
X-1078500D01*
Y-459200D01*
X-1079580Y-458380D01*
X-1080160Y-458100D01*
X-1082380D01*
X-1083280Y-458360D01*
X-1084020Y-458940D01*
X-1084340Y-459900D01*
X-1084060Y-460720D01*
X-1083740Y-461340D01*
X-1081860Y-462280D01*
X-1079400Y-462500D01*
X-1078660Y-462680D01*
X-1078100Y-462860D01*
X-1076500Y-463460D01*
X-1075320Y-463860D01*
X-1075060Y-464000D01*
X-1073820Y-465220D01*
X-1073480Y-466260D01*
X-1073300Y-467160D01*
Y-468420D01*
X-1073860Y-470700D01*
X-1074000Y-470960D01*
X-1075140Y-472300D01*
X-1075280Y-472440D01*
X-1076600Y-473380D01*
X-1077320Y-473740D01*
X-1079600Y-474500D01*
X-1088240D01*
X-1089160Y-474320D01*
X-1089920Y-474120D01*
X-1090860Y-473760D01*
X-1091560Y-473400D01*
X-1092700Y-472460D01*
X-1093180Y-471980D01*
X-1093340Y-471480D01*
X-1093520Y-471100D01*
X-1093700Y-470320D01*
X-1093780Y-468700D01*
G01X-1095100D02*
X-1092800D01*
G01X-1058300Y-469400D02*
X-1055400Y-467100D01*
X-1053900Y-463700D01*
X-1054400Y-461200D01*
X-1055900Y-459900D01*
X-1054800Y-463500D01*
X-1055400Y-463600D01*
X-1054600Y-464500D01*
X-1055700D01*
X-1055400Y-465300D01*
X-1056200Y-466800D01*
G01X-1059300Y-457700D02*
X-1059100Y-455600D01*
X-1055200Y-456300D01*
X-1052700Y-457900D01*
X-1051100Y-460800D01*
X-1050900Y-465200D01*
X-1052900Y-469400D01*
X-1055300Y-471900D01*
X-1059000Y-473500D01*
X-1066000D01*
X-1068000Y-471900D01*
X-1070200Y-468700D01*
X-1070600Y-464500D01*
X-1069000Y-460500D01*
X-1066000Y-457500D01*
X-1063000Y-456500D01*
X-1059200Y-456000D01*
X-1053000Y-458500D01*
X-1052000Y-461500D01*
Y-465700D01*
X-1053400Y-468600D01*
X-1055700Y-471000D01*
X-1058900Y-472600D01*
X-1063700Y-473000D01*
X-1065900Y-473600D01*
X-1068300Y-472900D01*
X-1070600Y-469300D01*
X-1065100Y-472600D01*
X-1060800Y-472200D01*
X-1057200Y-470700D01*
X-1055200Y-469100D01*
X-1053300Y-466500D01*
X-1052500Y-463400D01*
X-1052900Y-460100D01*
X-1057000Y-457400D01*
X-1058700Y-457200D01*
X-1057000Y-458500D01*
X-1055100Y-459800D01*
X-1053800Y-460900D01*
X-1053400Y-463100D01*
X-1053600Y-465600D01*
X-1054800Y-467500D01*
X-1056400Y-469200D01*
X-1058500Y-470200D01*
X-1060200Y-470700D01*
X-1061500Y-471400D01*
X-1063300Y-471600D01*
X-1065400Y-471500D01*
X-1069000Y-469300D01*
X-1069600Y-466400D01*
X-1069700Y-463700D01*
X-1068600Y-461200D01*
X-1066700Y-459200D01*
X-1063900Y-457600D01*
X-1061100Y-457000D01*
X-1059600D01*
X-1060200Y-457500D01*
X-1063300Y-458000D01*
X-1065300Y-459500D01*
X-1066900Y-460600D01*
X-1067900Y-462100D01*
X-1068800Y-464300D01*
X-1068700Y-466900D01*
X-1068200Y-469100D01*
X-1066900Y-470200D01*
X-1064300Y-470900D01*
X-1065700Y-469300D01*
X-1065800Y-465900D01*
X-1065300Y-462900D01*
X-1061200Y-458200D01*
X-1063600Y-458900D01*
X-1066400Y-461300D01*
X-1067800Y-464200D01*
Y-467200D01*
X-1067400Y-469300D01*
X-1066300Y-469700D01*
X-1067100Y-466400D01*
X-1066600Y-463400D01*
X-1064700Y-460000D01*
X-1062600Y-458800D01*
X-1065300Y-461700D01*
X-1066700Y-467400D01*
G01X-1060840Y-455100D02*
X-1057160D01*
X-1055260Y-455480D01*
X-1054740Y-455640D01*
X-1053380Y-456420D01*
X-1052660Y-456800D01*
X-1052020Y-457420D01*
X-1051820Y-458020D01*
X-1051200Y-458660D01*
X-1051000Y-459060D01*
X-1050840Y-459200D01*
X-1050700Y-459780D01*
Y-460140D01*
X-1050400Y-460460D01*
X-1050280Y-460680D01*
X-1050100Y-461740D01*
Y-464240D01*
X-1050280Y-465160D01*
X-1050480Y-465980D01*
X-1050680Y-467120D01*
X-1051220Y-468180D01*
X-1051840Y-469020D01*
X-1052040Y-469600D01*
X-1052740Y-470500D01*
X-1054480Y-472240D01*
X-1055000Y-472580D01*
X-1055420Y-472780D01*
X-1056220Y-473380D01*
X-1056920Y-473740D01*
X-1059380Y-474500D01*
X-1065600D01*
X-1067860Y-473740D01*
X-1068160Y-473600D01*
X-1069500Y-472460D01*
X-1069820Y-472120D01*
X-1070380Y-471200D01*
X-1071140Y-469860D01*
X-1071300Y-469400D01*
Y-464580D01*
X-1071120Y-463880D01*
X-1070740Y-462900D01*
X-1070540Y-462320D01*
X-1069980Y-461000D01*
X-1068840Y-459500D01*
X-1066900Y-457560D01*
X-1066180Y-457020D01*
X-1065400Y-456620D01*
X-1064440Y-456040D01*
X-1063500Y-455660D01*
X-1062940Y-455480D01*
X-1060840Y-455100D01*
G01X-1057800Y-458580D02*
X-1057000Y-459120D01*
X-1056760Y-459840D01*
X-1056340Y-460460D01*
X-1056100Y-461640D01*
Y-463760D01*
X-1056320Y-464860D01*
X-1056720Y-466060D01*
X-1056940Y-466920D01*
X-1057200Y-467460D01*
X-1057640Y-467880D01*
X-1058040Y-468480D01*
X-1059960Y-470420D01*
X-1061020Y-470840D01*
X-1061420Y-471100D01*
X-1062720D01*
X-1063340Y-470840D01*
X-1063860Y-470600D01*
X-1064360Y-470080D01*
X-1064820Y-469400D01*
X-1065100Y-468840D01*
Y-464920D01*
X-1064880Y-464120D01*
X-1064420Y-462780D01*
X-1064160Y-462520D01*
X-1063620Y-461700D01*
X-1063200Y-460840D01*
X-1062500Y-460140D01*
X-1062120Y-459860D01*
X-1061720Y-459360D01*
X-1060600Y-458580D01*
X-1060040Y-458300D01*
X-1058360D01*
X-1057800Y-458580D01*
G01X-1040300Y-459100D02*
X-1041400Y-464800D01*
G01X-1044800Y-458200D02*
X-1041400D01*
X-1044300Y-472700D01*
X-1047400Y-472300D01*
X-1044100Y-458800D01*
X-1042400Y-459100D01*
X-1045100Y-471900D01*
X-1046500D01*
X-1043400Y-459700D01*
X-1045600Y-471500D01*
G01X-1036600Y-449900D02*
X-1036800Y-451300D01*
X-1038600Y-452400D01*
X-1039800Y-456100D01*
X-1033700Y-456500D01*
X-1032300Y-452100D01*
X-1028400Y-452000D01*
X-1028900Y-455400D01*
X-1027200Y-456600D01*
X-1025900Y-456800D01*
X-1026200Y-458200D01*
X-1030000Y-458400D01*
X-1031800Y-468900D01*
X-1030400Y-471700D01*
X-1029400D01*
X-1029600Y-473300D01*
X-1033100Y-473400D01*
X-1036100Y-472800D01*
X-1036200Y-470500D01*
X-1035900Y-467100D01*
X-1034400Y-461400D01*
X-1033800Y-458800D01*
X-1033500Y-458400D01*
X-1035000Y-458200D01*
X-1039600D01*
X-1040800Y-458300D01*
X-1043600Y-473200D01*
X-1048000Y-473000D01*
X-1045100Y-459400D01*
X-1044900Y-458400D01*
X-1048700D01*
X-1048100Y-456600D01*
X-1044900Y-456400D01*
X-1045200Y-457700D01*
X-1047600Y-457500D01*
X-1026500D01*
G01X-1049580Y-459100D02*
X-1048740Y-455700D01*
X-1044900D01*
Y-454780D01*
X-1044720Y-454060D01*
X-1044340Y-452920D01*
X-1043940Y-452120D01*
X-1043740Y-451520D01*
X-1043600Y-451260D01*
X-1042340Y-450000D01*
X-1042080Y-449860D01*
X-1040580Y-449480D01*
X-1039440Y-449300D01*
X-1036140D01*
X-1035440Y-449400D01*
X-1035480Y-449540D01*
X-1035680Y-450360D01*
X-1035880Y-451280D01*
X-1036000Y-451900D01*
X-1036740D01*
X-1037060Y-452200D01*
X-1037860Y-452600D01*
X-1038220Y-452980D01*
X-1038480Y-453740D01*
X-1038960Y-455700D01*
X-1034020D01*
X-1033720Y-455080D01*
X-1033500Y-453400D01*
X-1032940Y-451100D01*
X-1027260D01*
X-1027280Y-451180D01*
X-1027480Y-452780D01*
X-1027860Y-454280D01*
X-1028100Y-454760D01*
Y-455700D01*
X-1024800D01*
X-1024880Y-455940D01*
X-1025080Y-456940D01*
X-1025280Y-457540D01*
X-1025480Y-458560D01*
X-1025620Y-459100D01*
X-1029100D01*
Y-460000D01*
X-1029280Y-460540D01*
X-1029480Y-461540D01*
X-1029680Y-462140D01*
X-1029880Y-462960D01*
X-1030100Y-464000D01*
X-1030280Y-465560D01*
X-1030480Y-466140D01*
X-1030680Y-467140D01*
X-1030880Y-467740D01*
X-1031040Y-468400D01*
X-1031300Y-468660D01*
Y-469800D01*
X-1030300Y-470560D01*
X-1029940Y-470900D01*
X-1028220D01*
X-1028680Y-472780D01*
X-1028880Y-474120D01*
Y-474140D01*
X-1030720Y-474300D01*
X-1032860D01*
X-1034380Y-474120D01*
X-1035860Y-473740D01*
X-1036640Y-473280D01*
X-1036960Y-472660D01*
X-1037100Y-472280D01*
Y-470160D01*
X-1036920Y-469260D01*
X-1036700Y-468640D01*
X-1036500Y-466840D01*
X-1036320Y-466260D01*
X-1036120Y-465260D01*
X-1035920Y-464660D01*
X-1035720Y-463660D01*
X-1035520Y-463060D01*
X-1035320Y-462060D01*
X-1035120Y-461440D01*
X-1034820Y-459100D01*
X-1039900D01*
Y-460220D01*
X-1040280Y-461780D01*
X-1040480Y-463380D01*
X-1041280Y-466540D01*
X-1041480Y-467140D01*
X-1041700Y-468200D01*
X-1041880Y-469760D01*
X-1042080Y-470340D01*
X-1042280Y-471360D01*
X-1042480Y-472140D01*
X-1042680Y-472740D01*
X-1042880Y-473740D01*
X-1042940Y-473900D01*
X-1049140D01*
X-1048300Y-470620D01*
X-1048100Y-469020D01*
X-1047920Y-468260D01*
X-1047720Y-467660D01*
X-1047520Y-466660D01*
X-1047320Y-466060D01*
X-1047120Y-465060D01*
X-1046920Y-464460D01*
X-1046700Y-463400D01*
X-1046500Y-462020D01*
X-1046140Y-460500D01*
X-1045900Y-460040D01*
Y-459100D01*
X-1049580D01*
G01X-1038400Y-451100D02*
X-1040600Y-455800D01*
X-1043300D01*
X-1041400Y-451300D01*
X-1038900Y-451000D01*
X-1041200Y-455000D01*
X-1042000Y-455100D01*
X-1040500Y-452000D01*
G01X-1037500Y-449800D02*
X-1037800Y-451000D01*
X-1038500Y-450100D01*
X-1042000Y-450700D01*
X-1043100Y-452300D01*
X-1044100Y-455100D01*
X-1044200Y-456600D01*
X-1036600Y-456800D01*
G01X-1031100Y-472500D02*
X-1031400Y-470900D01*
X-1031900Y-472200D01*
X-1035200D01*
Y-467600D01*
X-1032000Y-453700D01*
X-1030500Y-453800D01*
X-1030000Y-456700D01*
X-1033400Y-471900D01*
X-1034300Y-471600D01*
X-1034200Y-467100D01*
X-1031400Y-454500D01*
X-1030700Y-456500D01*
X-1033700Y-470600D01*
X-1032700Y-461100D01*
G01X-1032000Y-452900D02*
X-1029300D01*
X-1028000Y-457000D01*
X-1029500Y-453600D01*
X-1029100Y-457300D01*
X-1032800Y-472800D01*
X-1030200Y-472600D01*
G54D14*
X-1530728Y-162450D03*
X-1533728Y-154950D03*
X-1530228Y-146950D03*
X-1522728Y-165950D03*
X-1514728Y-162450D03*
X-1515228Y-146950D03*
X-1522728Y-143950D03*
X-1511728Y-154950D03*
X-663638D03*
X-652638Y-165950D03*
X-660638Y-162450D03*
X-660138Y-146950D03*
X-652638Y-143950D03*
X-641638Y-154950D03*
X-644638Y-162450D03*
X-645138Y-146950D03*
X-177597Y-89740D03*
X-185597Y-86240D03*
X-188597Y-78740D03*
X-185097Y-70740D03*
X-177597Y-67740D03*
X-169597Y-86240D03*
X-170097Y-70740D03*
X-166597Y-78740D03*
X-4110Y-167953D03*
X6890Y-178953D03*
X-1110Y-175453D03*
X14390Y-159953D03*
X-610D03*
X6890Y-156953D03*
X17890Y-167953D03*
X14890Y-175453D03*
G54D24*
G01X-1186050Y-540000D02*
Y-552500D01*
X-1180250D01*
G01X-1174975D02*
X-1171350Y-540000D01*
X-1167725Y-552500D01*
G01X-1169030Y-548125D02*
X-1173670D01*
G01X-1159550Y-552500D02*
Y-546875D01*
X-1162450Y-540000D01*
G01X-1156650D02*
X-1159550Y-546875D01*
G01X-1144850Y-552500D02*
X-1150650D01*
Y-540000D01*
X-1144850D01*
G01X-1147170Y-546042D02*
X-1150650D01*
G01X-1138850Y-552500D02*
Y-540000D01*
X-1135225D01*
X-1134065Y-540625D01*
X-1133340Y-541458D01*
X-1133050Y-543125D01*
X-1133340Y-544792D01*
X-1134210Y-545833D01*
X-1135225Y-546458D01*
X-1138850D01*
G01X-1135225D02*
X-1133050Y-552500D01*
G01X-1115540Y-550625D02*
X-1114670Y-551667D01*
X-1113655Y-552292D01*
X-1112350Y-552500D01*
X-1111045Y-552083D01*
X-1110030Y-551250D01*
X-1109305Y-549792D01*
X-1109160Y-548125D01*
X-1109450Y-546458D01*
X-1110175Y-545417D01*
X-1111190Y-544584D01*
X-1112205Y-544375D01*
X-1113220Y-544584D01*
X-1114525Y-545417D01*
X-1114090Y-540000D01*
X-1110175D01*
G54D15*
X-1356889Y-167165D03*
Y-118937D03*
X-1051613Y-167165D03*
Y-118937D03*
X-486810Y-167165D03*
Y-118937D03*
X-181534Y-167165D03*
Y-118937D03*
G54D25*
G01X-1652043Y-100921D02*
X-1649000Y-97878D01*
G01D02*
X-1645957Y-94835D01*
G01X-1652043D02*
X-1649000Y-97878D01*
G01D02*
X-1645957Y-100921D01*
G01X-1185925Y-592500D02*
X-1178575Y-577500D01*
G01X-1185925D02*
X-1178575Y-592500D01*
G01X-1168050D02*
X-1166825Y-592250D01*
X-1165425Y-591500D01*
X-1164550Y-590250D01*
X-1164200Y-588500D01*
X-1164550Y-586750D01*
X-1165600Y-585250D01*
X-1167175Y-584500D01*
X-1168925D01*
X-1169975Y-584000D01*
X-1170850Y-582750D01*
X-1171200Y-581000D01*
X-1170675Y-579250D01*
X-1169450Y-578000D01*
X-1168050Y-577500D01*
X-1166650Y-578000D01*
X-1165425Y-579250D01*
X-1164900Y-581000D01*
X-1165250Y-582750D01*
X-1166125Y-584000D01*
X-1167175Y-584500D01*
X-1168925D01*
X-1170500Y-585250D01*
X-1171550Y-586750D01*
X-1171900Y-588500D01*
X-1171550Y-590250D01*
X-1170675Y-591500D01*
X-1169275Y-592250D01*
X-1168050Y-592500D01*
G01X-1153850D02*
X-1152625Y-592250D01*
X-1151225Y-591500D01*
X-1150350Y-590250D01*
X-1150000Y-588500D01*
X-1150350Y-586750D01*
X-1151400Y-585250D01*
X-1152975Y-584500D01*
X-1154725D01*
X-1155775Y-584000D01*
X-1156650Y-582750D01*
X-1157000Y-581000D01*
X-1156475Y-579250D01*
X-1155250Y-578000D01*
X-1153850Y-577500D01*
X-1152450Y-578000D01*
X-1151225Y-579250D01*
X-1150700Y-581000D01*
X-1151050Y-582750D01*
X-1151925Y-584000D01*
X-1152975Y-584500D01*
X-1154725D01*
X-1156300Y-585250D01*
X-1157350Y-586750D01*
X-1157700Y-588500D01*
X-1157350Y-590250D01*
X-1156475Y-591500D01*
X-1155075Y-592250D01*
X-1153850Y-592500D01*
G01X-1140000D02*
X-1139650Y-589250D01*
X-1139125Y-586500D01*
X-1138425Y-584000D01*
X-1137550Y-581250D01*
X-1136150Y-577500D01*
X-1143150D01*
G01X-1129300Y-590250D02*
X-1128250Y-591500D01*
X-1127025Y-592250D01*
X-1125450Y-592500D01*
X-1123875Y-592000D01*
X-1122650Y-591000D01*
X-1121775Y-589250D01*
X-1121600Y-587250D01*
X-1121950Y-585250D01*
X-1122825Y-584000D01*
X-1124050Y-583000D01*
X-1125275Y-582750D01*
X-1126500Y-583000D01*
X-1128075Y-584000D01*
X-1127550Y-577500D01*
X-1122825D01*
G01X-1111600Y-592500D02*
X-1111250Y-589250D01*
X-1110725Y-586500D01*
X-1110025Y-584000D01*
X-1109150Y-581250D01*
X-1107750Y-577500D01*
X-1114750D01*
G01X-1097050Y-592500D02*
Y-577500D01*
X-1099150Y-580500D01*
G01Y-592500D02*
X-1094950D01*
G01X-1085125Y-587500D02*
X-1080575D01*
G01X-1068650Y-577500D02*
X-1070050Y-578000D01*
X-1071100Y-579250D01*
X-1071800Y-580750D01*
X-1072325Y-582750D01*
X-1072500Y-585000D01*
X-1072325Y-587250D01*
X-1071800Y-589250D01*
X-1071100Y-590750D01*
X-1070050Y-592000D01*
X-1068650Y-592500D01*
X-1067250Y-592000D01*
X-1066200Y-590750D01*
X-1065500Y-589250D01*
X-1064975Y-587250D01*
X-1064800Y-585000D01*
X-1064975Y-582750D01*
X-1065500Y-580750D01*
X-1066200Y-579250D01*
X-1067250Y-578000D01*
X-1068650Y-577500D01*
G01X-1054450D02*
X-1055850Y-578000D01*
X-1056900Y-579250D01*
X-1057600Y-580750D01*
X-1058125Y-582750D01*
X-1058300Y-585000D01*
X-1058125Y-587250D01*
X-1057600Y-589250D01*
X-1056900Y-590750D01*
X-1055850Y-592000D01*
X-1054450Y-592500D01*
X-1053050Y-592000D01*
X-1052000Y-590750D01*
X-1051300Y-589250D01*
X-1050775Y-587250D01*
X-1050600Y-585000D01*
X-1050775Y-582750D01*
X-1051300Y-580750D01*
X-1052000Y-579250D01*
X-1053050Y-578000D01*
X-1054450Y-577500D01*
G01X-1044100Y-590250D02*
X-1043050Y-591500D01*
X-1041825Y-592250D01*
X-1040250Y-592500D01*
X-1038675Y-592000D01*
X-1037450Y-591000D01*
X-1036575Y-589250D01*
X-1036400Y-587250D01*
X-1036750Y-585250D01*
X-1037625Y-584000D01*
X-1038850Y-583000D01*
X-1040075Y-582750D01*
X-1041300Y-583000D01*
X-1042875Y-584000D01*
X-1042350Y-577500D01*
X-1037625D01*
G01X-911875Y-592500D02*
X-907500Y-577500D01*
X-903125Y-592500D01*
G01X-904700Y-587250D02*
X-910300D01*
G01X-810781Y-87027D02*
X-806854Y-83100D01*
G01D02*
X-802927Y-79173D01*
G01X-810781D02*
X-806854Y-83100D01*
G01D02*
X-802927Y-87027D01*
G01X-789127D02*
X-785200Y-83100D01*
G01X-789127Y-79173D02*
X-785200Y-83100D01*
G01D02*
X-781273Y-87027D01*
G01X-785200Y-83100D02*
X-781273Y-79173D01*
G54D16*
X-1253740Y-184094D03*
X-1225394D03*
X-1207677Y-154567D03*
X-412402Y-172283D03*
Y-130157D03*
Y-94724D03*
Y-59291D03*
Y-23858D03*
X-383661Y-184094D03*
X-355315D03*
X-337598Y-154567D03*
Y-112441D03*
Y-77008D03*
Y-41575D03*
Y-6142D03*
G54D26*
G01X-1200000Y-560000D02*
X-890000D01*
G01Y-520000D02*
X-1200000D01*
G01X-575000Y-480000D02*
X-1200000D01*
G01X-927500Y-560000D02*
Y-600000D01*
G01X-915000Y-440000D02*
Y-480000D01*
G01X-890000D02*
Y-600000D01*
G01X-870000Y-440000D02*
Y-480000D01*
G01X-680000D02*
Y-440000D01*
G01X-1200000Y-600000D02*
X-575000D01*
Y-440000D01*
X-1200000D01*
Y-600000D01*
G54D17*
X-1025000Y-50942D03*
X-1015157Y-105312D03*
X-997441D03*
X-981693Y-50942D03*
X-971850Y-105312D03*
X-954134D03*
X-938386Y-50942D03*
X-145079Y-105312D03*
X-154921Y-50942D03*
Y1459D03*
X-127362Y-105312D03*
X-111614Y-50942D03*
Y1459D03*
X-101772Y-105312D03*
X-84055D03*
X-68307Y-50942D03*
Y1459D03*
G54D27*
G01X-1007500Y-470000D02*
X-1006450Y-475000D01*
X-1005250Y-470000D01*
X-1004050Y-475000D01*
X-1003000Y-470000D01*
G01X-1001125Y-475000D02*
X-999250Y-470000D01*
X-997375Y-475000D01*
G01X-998050Y-473250D02*
X-1000450D01*
G01X-994825Y-474333D02*
X-994225Y-474750D01*
X-993550Y-475000D01*
X-992950D01*
X-992350Y-474750D01*
X-991900Y-474333D01*
X-991675Y-473750D01*
X-991825Y-473167D01*
X-992200Y-472667D01*
X-992875Y-472333D01*
X-993775Y-472167D01*
X-994300Y-471833D01*
X-994525Y-471250D01*
X-994375Y-470667D01*
X-994000Y-470250D01*
X-993475Y-470000D01*
X-992950D01*
X-992425Y-470167D01*
X-991975Y-470583D01*
G01X-988825Y-475000D02*
Y-470000D01*
G01X-985675D02*
Y-475000D01*
G01Y-472500D02*
X-988825D01*
G01X-976525Y-474417D02*
X-976000Y-474833D01*
X-975400Y-475000D01*
X-974800Y-474833D01*
X-974275Y-474333D01*
X-973900Y-473583D01*
X-973750Y-472833D01*
Y-471917D01*
X-973900Y-471167D01*
X-974275Y-470500D01*
X-974725Y-470167D01*
X-975250Y-470000D01*
X-975850Y-470167D01*
X-976300Y-470500D01*
X-976600Y-471000D01*
X-976750Y-471667D01*
X-976600Y-472250D01*
X-976225Y-472833D01*
X-975775Y-473167D01*
X-975250Y-473250D01*
X-974650Y-473083D01*
X-974200Y-472667D01*
X-973750Y-471917D01*
G01X-969250Y-475000D02*
X-968725Y-474917D01*
X-968125Y-474667D01*
X-967750Y-474250D01*
X-967600Y-473667D01*
X-967750Y-473083D01*
X-968200Y-472583D01*
X-968875Y-472333D01*
X-969625D01*
X-970075Y-472167D01*
X-970450Y-471750D01*
X-970600Y-471167D01*
X-970375Y-470583D01*
X-969850Y-470167D01*
X-969250Y-470000D01*
X-968650Y-470167D01*
X-968125Y-470583D01*
X-967900Y-471167D01*
X-968050Y-471750D01*
X-968425Y-472167D01*
X-968875Y-472333D01*
X-969625D01*
X-970300Y-472583D01*
X-970750Y-473083D01*
X-970900Y-473667D01*
X-970750Y-474250D01*
X-970375Y-474667D01*
X-969775Y-474917D01*
X-969250Y-475000D01*
G01X-963250Y-470000D02*
X-963850Y-470167D01*
X-964300Y-470583D01*
X-964600Y-471083D01*
X-964825Y-471750D01*
X-964900Y-472500D01*
X-964825Y-473250D01*
X-964600Y-473917D01*
X-964300Y-474417D01*
X-963850Y-474833D01*
X-963250Y-475000D01*
X-962650Y-474833D01*
X-962200Y-474417D01*
X-961900Y-473917D01*
X-961675Y-473250D01*
X-961600Y-472500D01*
X-961675Y-471750D01*
X-961900Y-471083D01*
X-962200Y-470583D01*
X-962650Y-470167D01*
X-963250Y-470000D01*
G01X-958900Y-474250D02*
X-958450Y-474667D01*
X-957925Y-474917D01*
X-957250Y-475000D01*
X-956575Y-474833D01*
X-956050Y-474500D01*
X-955675Y-473917D01*
X-955600Y-473250D01*
X-955750Y-472583D01*
X-956125Y-472167D01*
X-956650Y-471833D01*
X-957175Y-471750D01*
X-957700Y-471833D01*
X-958375Y-472167D01*
X-958150Y-470000D01*
X-956125D01*
G01X-952675Y-470833D02*
X-952225Y-470333D01*
X-951700Y-470083D01*
X-951100Y-470000D01*
X-950350Y-470167D01*
X-949825Y-470583D01*
X-949675Y-471083D01*
X-949750Y-471583D01*
X-950050Y-472000D01*
X-951550Y-472833D01*
X-952225Y-473417D01*
X-952675Y-474250D01*
X-952825Y-475000D01*
X-949675D01*
G01X-946225Y-473333D02*
X-944275D01*
G01X-940675Y-472917D02*
X-940150Y-472333D01*
X-939700Y-472000D01*
X-939100Y-471833D01*
X-938575Y-472000D01*
X-938200Y-472333D01*
X-937900Y-472833D01*
X-937825Y-473417D01*
X-937900Y-473917D01*
X-938200Y-474417D01*
X-938650Y-474833D01*
X-939175Y-475000D01*
X-939775Y-474833D01*
X-940300Y-474333D01*
X-940600Y-473583D01*
X-940675Y-472750D01*
X-940525Y-471667D01*
X-940300Y-471083D01*
X-939925Y-470500D01*
X-939400Y-470083D01*
X-938875Y-470000D01*
X-938350Y-470167D01*
X-937975Y-470583D01*
G01X-934900Y-474000D02*
X-934450Y-474583D01*
X-933850Y-474917D01*
X-933175Y-475000D01*
X-932575Y-474917D01*
X-931975Y-474500D01*
X-931600Y-474000D01*
X-931525Y-473500D01*
X-931675Y-472917D01*
X-932200Y-472500D01*
X-932725Y-472333D01*
X-933400D01*
G01X-932725D02*
X-932275Y-472083D01*
X-931900Y-471667D01*
X-931750Y-471167D01*
X-931900Y-470667D01*
X-932275Y-470250D01*
X-932950Y-470000D01*
X-933625Y-470083D01*
X-934300Y-470417D01*
G01X-928525Y-474417D02*
X-928000Y-474833D01*
X-927400Y-475000D01*
X-926800Y-474833D01*
X-926275Y-474333D01*
X-925900Y-473583D01*
X-925750Y-472833D01*
Y-471917D01*
X-925900Y-471167D01*
X-926275Y-470500D01*
X-926725Y-470167D01*
X-927250Y-470000D01*
X-927850Y-470167D01*
X-928300Y-470500D01*
X-928600Y-471000D01*
X-928750Y-471667D01*
X-928600Y-472250D01*
X-928225Y-472833D01*
X-927775Y-473167D01*
X-927250Y-473250D01*
X-926650Y-473083D01*
X-926200Y-472667D01*
X-925750Y-471917D01*
G01X-922525Y-474417D02*
X-922000Y-474833D01*
X-921400Y-475000D01*
X-920800Y-474833D01*
X-920275Y-474333D01*
X-919900Y-473583D01*
X-919750Y-472833D01*
Y-471917D01*
X-919900Y-471167D01*
X-920275Y-470500D01*
X-920725Y-470167D01*
X-921250Y-470000D01*
X-921850Y-470167D01*
X-922300Y-470500D01*
X-922600Y-471000D01*
X-922750Y-471667D01*
X-922600Y-472250D01*
X-922225Y-472833D01*
X-921775Y-473167D01*
X-921250Y-473250D01*
X-920650Y-473083D01*
X-920200Y-472667D01*
X-919750Y-471917D01*
G01X-1006750Y-465000D02*
Y-460000D01*
X-1004875D01*
X-1004275Y-460250D01*
X-1003900Y-460583D01*
X-1003750Y-461250D01*
X-1003900Y-461917D01*
X-1004350Y-462333D01*
X-1004875Y-462583D01*
X-1006750D01*
G01X-1004875D02*
X-1003750Y-465000D01*
G01X-997750D02*
X-1000750D01*
Y-460000D01*
X-997750D01*
G01X-998950Y-462417D02*
X-1000750D01*
G01X-994900Y-465000D02*
Y-460000D01*
X-993400D01*
X-992800Y-460250D01*
X-992350Y-460583D01*
X-991975Y-461083D01*
X-991675Y-461667D01*
X-991600Y-462500D01*
X-991675Y-463333D01*
X-991975Y-463917D01*
X-992350Y-464417D01*
X-992800Y-464750D01*
X-993400Y-465000D01*
X-994900D01*
G01X-989200D02*
Y-460000D01*
X-987250Y-464167D01*
X-985300Y-460000D01*
Y-465000D01*
G01X-981250D02*
X-981850Y-464917D01*
X-982375Y-464583D01*
X-982825Y-464083D01*
X-983125Y-463500D01*
X-983275Y-462833D01*
Y-462167D01*
X-983125Y-461500D01*
X-982825Y-460917D01*
X-982375Y-460417D01*
X-981850Y-460083D01*
X-981250Y-460000D01*
X-980650Y-460083D01*
X-980125Y-460417D01*
X-979675Y-460917D01*
X-979375Y-461500D01*
X-979225Y-462167D01*
Y-462833D01*
X-979375Y-463500D01*
X-979675Y-464083D01*
X-980125Y-464583D01*
X-980650Y-464917D01*
X-981250Y-465000D01*
G01X-976975D02*
Y-460000D01*
X-973525Y-465000D01*
Y-460000D01*
G01X-970900Y-465000D02*
Y-460000D01*
X-969400D01*
X-968800Y-460250D01*
X-968350Y-460583D01*
X-967975Y-461083D01*
X-967675Y-461667D01*
X-967600Y-462500D01*
X-967675Y-463333D01*
X-967975Y-463917D01*
X-968350Y-464417D01*
X-968800Y-464750D01*
X-969400Y-465000D01*
X-970900D01*
G01X-1005250Y-455000D02*
Y-450000D01*
X-1006150Y-451000D01*
G01Y-455000D02*
X-1004350D01*
G01X-995200D02*
Y-450000D01*
X-993250Y-454167D01*
X-991300Y-450000D01*
Y-455000D01*
G01X-988150Y-450000D02*
X-986350D01*
G01X-987250D02*
Y-455000D01*
G01X-988150D02*
X-986350D01*
G01X-979600Y-450417D02*
X-980050Y-450167D01*
X-980575Y-450000D01*
X-981175D01*
X-981850Y-450250D01*
X-982375Y-450667D01*
X-982750Y-451167D01*
X-983050Y-452000D01*
X-983125Y-452750D01*
X-982975Y-453500D01*
X-982750Y-454000D01*
X-982300Y-454500D01*
X-981775Y-454833D01*
X-981250Y-455000D01*
X-980725D01*
X-980200Y-454833D01*
X-979750Y-454583D01*
X-979375Y-454250D01*
G01X-976750Y-455000D02*
Y-450000D01*
X-974875D01*
X-974275Y-450250D01*
X-973900Y-450583D01*
X-973750Y-451250D01*
X-973900Y-451917D01*
X-974350Y-452333D01*
X-974875Y-452583D01*
X-976750D01*
G01X-974875D02*
X-973750Y-455000D01*
G01X-969250D02*
X-969850Y-454917D01*
X-970375Y-454583D01*
X-970825Y-454083D01*
X-971125Y-453500D01*
X-971275Y-452833D01*
Y-452167D01*
X-971125Y-451500D01*
X-970825Y-450917D01*
X-970375Y-450417D01*
X-969850Y-450083D01*
X-969250Y-450000D01*
X-968650Y-450083D01*
X-968125Y-450417D01*
X-967675Y-450917D01*
X-967375Y-451500D01*
X-967225Y-452167D01*
Y-452833D01*
X-967375Y-453500D01*
X-967675Y-454083D01*
X-968125Y-454583D01*
X-968650Y-454917D01*
X-969250Y-455000D01*
G01X-964825Y-454333D02*
X-964225Y-454750D01*
X-963550Y-455000D01*
X-962950D01*
X-962350Y-454750D01*
X-961900Y-454333D01*
X-961675Y-453750D01*
X-961825Y-453167D01*
X-962200Y-452667D01*
X-962875Y-452333D01*
X-963775Y-452167D01*
X-964300Y-451833D01*
X-964525Y-451250D01*
X-964375Y-450667D01*
X-964000Y-450250D01*
X-963475Y-450000D01*
X-962950D01*
X-962425Y-450167D01*
X-961975Y-450583D01*
G01X-957250Y-455000D02*
X-957850Y-454917D01*
X-958375Y-454583D01*
X-958825Y-454083D01*
X-959125Y-453500D01*
X-959275Y-452833D01*
Y-452167D01*
X-959125Y-451500D01*
X-958825Y-450917D01*
X-958375Y-450417D01*
X-957850Y-450083D01*
X-957250Y-450000D01*
X-956650Y-450083D01*
X-956125Y-450417D01*
X-955675Y-450917D01*
X-955375Y-451500D01*
X-955225Y-452167D01*
Y-452833D01*
X-955375Y-453500D01*
X-955675Y-454083D01*
X-956125Y-454583D01*
X-956650Y-454917D01*
X-957250Y-455000D01*
G01X-952675D02*
Y-450000D01*
X-949825D01*
G01X-950875Y-452417D02*
X-952675D01*
G01X-945250Y-450000D02*
Y-455000D01*
G01X-946975Y-450000D02*
X-943525D01*
G01X-935500D02*
X-934450Y-455000D01*
X-933250Y-450000D01*
X-932050Y-455000D01*
X-931000Y-450000D01*
G01X-929125Y-455000D02*
X-927250Y-450000D01*
X-925375Y-455000D01*
G01X-926050Y-453250D02*
X-928450D01*
G01X-921250Y-455000D02*
Y-452750D01*
X-922750Y-450000D01*
G01X-919750D02*
X-921250Y-452750D01*
G54D18*
X-1015157Y-95824D03*
Y-80864D03*
Y-65903D03*
Y-50942D03*
X-1006299Y-95824D03*
X-997441D03*
X-1006299Y-80864D03*
X-997441D03*
X-1006299Y-65903D03*
X-997441D03*
X-1006299Y-50942D03*
X-997441D03*
X-971850Y-95824D03*
X-962992D03*
X-971850Y-80864D03*
X-962992D03*
X-971850Y-65903D03*
X-962992D03*
X-971850Y-50942D03*
X-962992D03*
X-954134Y-95824D03*
Y-80864D03*
Y-65903D03*
Y-50942D03*
X-145079Y-95824D03*
Y-80864D03*
Y-65903D03*
Y-50942D03*
X-136220Y-95824D03*
X-127362D03*
X-136220Y-80864D03*
X-127362D03*
X-136220Y-65903D03*
X-127362D03*
X-136220Y-50942D03*
X-127362D03*
X-101772Y-95824D03*
Y-80864D03*
Y-65903D03*
Y-50942D03*
X-92913Y-95824D03*
X-84055D03*
X-92913Y-80864D03*
X-84055D03*
X-92913Y-65903D03*
X-84055D03*
X-92913Y-50942D03*
X-84055D03*
G54D28*
G01X-874510Y-499000D02*
Y-493000D01*
X-871290Y-499000D01*
Y-493000D01*
G01X-867200Y-499000D02*
X-867760Y-498900D01*
X-868250Y-498500D01*
X-868670Y-497900D01*
X-868950Y-497200D01*
X-869090Y-496400D01*
Y-495600D01*
X-868950Y-494800D01*
X-868670Y-494100D01*
X-868250Y-493500D01*
X-867760Y-493100D01*
X-867200Y-493000D01*
X-866640Y-493100D01*
X-866150Y-493500D01*
X-865730Y-494100D01*
X-865450Y-494800D01*
X-865310Y-495600D01*
Y-496400D01*
X-865450Y-497200D01*
X-865730Y-497900D01*
X-866150Y-498500D01*
X-866640Y-498900D01*
X-867200Y-499000D01*
G01X-861500Y-493000D02*
Y-499000D01*
G01X-863110Y-493000D02*
X-859890D01*
G01X-856640D02*
X-854960D01*
G01X-855800D02*
Y-499000D01*
G01X-856640D02*
X-854960D01*
G01X-848560Y-493500D02*
X-848980Y-493200D01*
X-849470Y-493000D01*
X-850030D01*
X-850660Y-493300D01*
X-851150Y-493800D01*
X-851500Y-494400D01*
X-851780Y-495400D01*
X-851850Y-496300D01*
X-851710Y-497200D01*
X-851500Y-497800D01*
X-851080Y-498400D01*
X-850590Y-498800D01*
X-850100Y-499000D01*
X-849610D01*
X-849120Y-498800D01*
X-848700Y-498500D01*
X-848350Y-498100D01*
G01X-843000Y-499000D02*
X-845800D01*
Y-493000D01*
X-843000D01*
G01X-844120Y-495900D02*
X-845800D01*
G01X-833000Y-499000D02*
X-833560Y-498900D01*
X-834050Y-498500D01*
X-834470Y-497900D01*
X-834750Y-497200D01*
X-834890Y-496400D01*
Y-495600D01*
X-834750Y-494800D01*
X-834470Y-494100D01*
X-834050Y-493500D01*
X-833560Y-493100D01*
X-833000Y-493000D01*
X-832440Y-493100D01*
X-831950Y-493500D01*
X-831530Y-494100D01*
X-831250Y-494800D01*
X-831110Y-495600D01*
Y-496400D01*
X-831250Y-497200D01*
X-831530Y-497900D01*
X-831950Y-498500D01*
X-832440Y-498900D01*
X-833000Y-499000D01*
G01X-828630D02*
Y-493000D01*
X-825970D01*
G01X-826950Y-495900D02*
X-828630D01*
G01X-817300Y-499000D02*
Y-493000D01*
X-815620D01*
X-815060Y-493300D01*
X-814640Y-494000D01*
X-814500Y-494800D01*
X-814640Y-495600D01*
X-814990Y-496200D01*
X-815620Y-496500D01*
X-817300D01*
G01X-811600Y-499000D02*
Y-493000D01*
X-809850D01*
X-809290Y-493300D01*
X-808940Y-493700D01*
X-808800Y-494500D01*
X-808940Y-495300D01*
X-809360Y-495800D01*
X-809850Y-496100D01*
X-811600D01*
G01X-809850D02*
X-808800Y-499000D01*
G01X-804500D02*
X-805060Y-498900D01*
X-805550Y-498500D01*
X-805970Y-497900D01*
X-806250Y-497200D01*
X-806390Y-496400D01*
Y-495600D01*
X-806250Y-494800D01*
X-805970Y-494100D01*
X-805550Y-493500D01*
X-805060Y-493100D01*
X-804500Y-493000D01*
X-803940Y-493100D01*
X-803450Y-493500D01*
X-803030Y-494100D01*
X-802750Y-494800D01*
X-802610Y-495600D01*
Y-496400D01*
X-802750Y-497200D01*
X-803030Y-497900D01*
X-803450Y-498500D01*
X-803940Y-498900D01*
X-804500Y-499000D01*
G01X-800200D02*
Y-493000D01*
X-798520D01*
X-797960Y-493300D01*
X-797540Y-494000D01*
X-797400Y-494800D01*
X-797540Y-495600D01*
X-797890Y-496200D01*
X-798520Y-496500D01*
X-800200D01*
G01X-794500Y-499000D02*
Y-493000D01*
X-792750D01*
X-792190Y-493300D01*
X-791840Y-493700D01*
X-791700Y-494500D01*
X-791840Y-495300D01*
X-792260Y-495800D01*
X-792750Y-496100D01*
X-794500D01*
G01X-792750D02*
X-791700Y-499000D01*
G01X-788240Y-493000D02*
X-786560D01*
G01X-787400D02*
Y-499000D01*
G01X-788240D02*
X-786560D01*
G01X-780300D02*
X-783100D01*
Y-493000D01*
X-780300D01*
G01X-781420Y-495900D02*
X-783100D01*
G01X-776000Y-493000D02*
Y-499000D01*
G01X-777610Y-493000D02*
X-774390D01*
G01X-772050Y-499000D02*
X-770300Y-493000D01*
X-768550Y-499000D01*
G01X-769180Y-496900D02*
X-771420D01*
G01X-766000Y-499000D02*
Y-493000D01*
X-764250D01*
X-763690Y-493300D01*
X-763340Y-493700D01*
X-763200Y-494500D01*
X-763340Y-495300D01*
X-763760Y-495800D01*
X-764250Y-496100D01*
X-766000D01*
G01X-764250D02*
X-763200Y-499000D01*
G01X-758900D02*
Y-496300D01*
X-760300Y-493000D01*
G01X-757500D02*
X-758900Y-496300D01*
G01X-748900Y-499000D02*
Y-493000D01*
X-747220D01*
X-746660Y-493300D01*
X-746240Y-494000D01*
X-746100Y-494800D01*
X-746240Y-495600D01*
X-746590Y-496200D01*
X-747220Y-496500D01*
X-748900D01*
G01X-743200Y-499000D02*
Y-493000D01*
X-741450D01*
X-740890Y-493300D01*
X-740540Y-493700D01*
X-740400Y-494500D01*
X-740540Y-495300D01*
X-740960Y-495800D01*
X-741450Y-496100D01*
X-743200D01*
G01X-741450D02*
X-740400Y-499000D01*
G01X-736100D02*
X-736660Y-498900D01*
X-737150Y-498500D01*
X-737570Y-497900D01*
X-737850Y-497200D01*
X-737990Y-496400D01*
Y-495600D01*
X-737850Y-494800D01*
X-737570Y-494100D01*
X-737150Y-493500D01*
X-736660Y-493100D01*
X-736100Y-493000D01*
X-735540Y-493100D01*
X-735050Y-493500D01*
X-734630Y-494100D01*
X-734350Y-494800D01*
X-734210Y-495600D01*
Y-496400D01*
X-734350Y-497200D01*
X-734630Y-497900D01*
X-735050Y-498500D01*
X-735540Y-498900D01*
X-736100Y-499000D01*
G01X-731800D02*
Y-493000D01*
X-730120D01*
X-729560Y-493300D01*
X-729140Y-494000D01*
X-729000Y-494800D01*
X-729140Y-495600D01*
X-729490Y-496200D01*
X-730120Y-496500D01*
X-731800D01*
G01X-723300Y-499000D02*
X-726100D01*
Y-493000D01*
X-723300D01*
G01X-724420Y-495900D02*
X-726100D01*
G01X-720400Y-499000D02*
Y-493000D01*
X-718650D01*
X-718090Y-493300D01*
X-717740Y-493700D01*
X-717600Y-494500D01*
X-717740Y-495300D01*
X-718160Y-495800D01*
X-718650Y-496100D01*
X-720400D01*
G01X-718650D02*
X-717600Y-499000D01*
G01X-713300Y-493000D02*
Y-499000D01*
G01X-714910Y-493000D02*
X-711690D01*
G01X-707600Y-499000D02*
Y-496300D01*
X-709000Y-493000D01*
G01X-706200D02*
X-707600Y-496300D01*
G01X-701900Y-499200D02*
X-702040Y-499100D01*
Y-498900D01*
X-701900Y-498800D01*
X-701760Y-498900D01*
Y-499100D01*
X-701900Y-499200D01*
G01Y-496500D02*
X-702040Y-496400D01*
Y-496200D01*
X-701900Y-496100D01*
X-701760Y-496200D01*
Y-496400D01*
X-701900Y-496500D01*
G54D19*
X-806854Y-83100D03*
X-785200D03*
X-271161Y-142362D03*
Y-102992D03*
Y-63622D03*
Y-24252D03*
X-258681Y-83307D03*
X-237421D03*
X-248839Y-4567D03*
X-215059Y-122677D03*
Y-83307D03*
Y-43937D03*
Y-4567D03*
G54D29*
G01X-1189333Y-572500D02*
Y-565500D01*
X-1187667D01*
X-1187000Y-565850D01*
X-1186500Y-566317D01*
X-1186083Y-567017D01*
X-1185750Y-567833D01*
X-1185667Y-569000D01*
X-1185750Y-570167D01*
X-1186083Y-570983D01*
X-1186500Y-571684D01*
X-1187000Y-572150D01*
X-1187667Y-572500D01*
X-1189333D01*
G01X-1180700D02*
X-1181367Y-572383D01*
X-1181950Y-571917D01*
X-1182450Y-571217D01*
X-1182783Y-570400D01*
X-1182950Y-569467D01*
Y-568533D01*
X-1182783Y-567600D01*
X-1182450Y-566783D01*
X-1181950Y-566083D01*
X-1181367Y-565617D01*
X-1180700Y-565500D01*
X-1180033Y-565617D01*
X-1179450Y-566083D01*
X-1178950Y-566783D01*
X-1178617Y-567600D01*
X-1178450Y-568533D01*
Y-569467D01*
X-1178617Y-570400D01*
X-1178950Y-571217D01*
X-1179450Y-571917D01*
X-1180033Y-572383D01*
X-1180700Y-572500D01*
G01X-1172067Y-566083D02*
X-1172567Y-565733D01*
X-1173150Y-565500D01*
X-1173817D01*
X-1174567Y-565850D01*
X-1175150Y-566433D01*
X-1175567Y-567133D01*
X-1175900Y-568300D01*
X-1175983Y-569350D01*
X-1175817Y-570400D01*
X-1175567Y-571100D01*
X-1175067Y-571800D01*
X-1174483Y-572267D01*
X-1173900Y-572500D01*
X-1173317D01*
X-1172733Y-572267D01*
X-1172233Y-571917D01*
X-1171817Y-571450D01*
G01X-1168933Y-565500D02*
Y-570517D01*
X-1168600Y-571567D01*
X-1167933Y-572267D01*
X-1167100Y-572500D01*
X-1166267Y-572267D01*
X-1165600Y-571567D01*
X-1165267Y-570517D01*
Y-565500D01*
G01X-1162467Y-572500D02*
Y-565500D01*
X-1160300Y-571333D01*
X-1158133Y-565500D01*
Y-572500D01*
G01X-1151833D02*
X-1155167D01*
Y-565500D01*
X-1151833D01*
G01X-1153167Y-568883D02*
X-1155167D01*
G01X-1148617Y-572500D02*
Y-565500D01*
X-1144783Y-572500D01*
Y-565500D01*
G01X-1139900D02*
Y-572500D01*
G01X-1141817Y-565500D02*
X-1137983D01*
G01X-1128217Y-572500D02*
Y-565500D01*
X-1124383Y-572500D01*
Y-565500D01*
G01X-1121333D02*
Y-570517D01*
X-1121000Y-571567D01*
X-1120333Y-572267D01*
X-1119500Y-572500D01*
X-1118667Y-572267D01*
X-1118000Y-571567D01*
X-1117667Y-570517D01*
Y-565500D01*
G01X-1114867Y-572500D02*
Y-565500D01*
X-1112700Y-571333D01*
X-1110533Y-565500D01*
Y-572500D01*
G01X-1105233Y-568767D02*
X-1104900Y-568417D01*
X-1104650Y-567833D01*
X-1104483Y-567017D01*
X-1104650Y-566317D01*
X-1104983Y-565850D01*
X-1105567Y-565500D01*
X-1107817D01*
Y-572500D01*
X-1105067D01*
X-1104483Y-572033D01*
X-1104150Y-571333D01*
X-1103983Y-570517D01*
X-1104150Y-569700D01*
X-1104650Y-569000D01*
X-1105233Y-568767D01*
X-1107817D01*
G01X-1097433Y-572500D02*
X-1100767D01*
Y-565500D01*
X-1097433D01*
G01X-1098767Y-568883D02*
X-1100767D01*
G01X-1093967Y-572500D02*
Y-565500D01*
X-1091883D01*
X-1091217Y-565850D01*
X-1090800Y-566317D01*
X-1090633Y-567250D01*
X-1090800Y-568183D01*
X-1091300Y-568767D01*
X-1091883Y-569117D01*
X-1093967D01*
G01X-1091883D02*
X-1090633Y-572500D01*
G01X-1189250Y-531567D02*
X-1188583Y-532150D01*
X-1187833Y-532500D01*
X-1187167D01*
X-1186500Y-532150D01*
X-1186000Y-531567D01*
X-1185750Y-530750D01*
X-1185917Y-529933D01*
X-1186333Y-529233D01*
X-1187083Y-528767D01*
X-1188083Y-528533D01*
X-1188667Y-528067D01*
X-1188917Y-527250D01*
X-1188750Y-526433D01*
X-1188333Y-525850D01*
X-1187750Y-525500D01*
X-1187167D01*
X-1186583Y-525733D01*
X-1186083Y-526317D01*
G01X-1182450Y-532500D02*
Y-525500D01*
G01X-1178950D02*
Y-532500D01*
G01Y-529000D02*
X-1182450D01*
G01X-1172233Y-532500D02*
X-1175567D01*
Y-525500D01*
X-1172233D01*
G01X-1173567Y-528883D02*
X-1175567D01*
G01X-1165433Y-532500D02*
X-1168767D01*
Y-525500D01*
X-1165433D01*
G01X-1166767Y-528883D02*
X-1168767D01*
G01X-1160300Y-525500D02*
Y-532500D01*
G01X-1162217Y-525500D02*
X-1158383D01*
G01X-1146700D02*
Y-532500D01*
G01X-1148617Y-525500D02*
X-1144783D01*
G01X-1140900D02*
X-1138900D01*
G01X-1139900D02*
Y-532500D01*
G01X-1140900D02*
X-1138900D01*
G01X-1133100Y-525500D02*
Y-532500D01*
G01X-1135017Y-525500D02*
X-1131183D01*
G01X-1127967D02*
Y-532500D01*
X-1124633D01*
G01X-1117833D02*
X-1121167D01*
Y-525500D01*
X-1117833D01*
G01X-1119167Y-528883D02*
X-1121167D01*
G01X-1112700Y-532733D02*
X-1112867Y-532617D01*
Y-532383D01*
X-1112700Y-532267D01*
X-1112533Y-532383D01*
Y-532617D01*
X-1112700Y-532733D01*
G01Y-529584D02*
X-1112867Y-529467D01*
Y-529233D01*
X-1112700Y-529117D01*
X-1112533Y-529233D01*
Y-529467D01*
X-1112700Y-529584D01*
G01X-1187500Y-485500D02*
Y-492500D01*
G01X-1189417Y-485500D02*
X-1185583D01*
G01X-1181700D02*
X-1179700D01*
G01X-1180700D02*
Y-492500D01*
G01X-1181700D02*
X-1179700D01*
G01X-1173900Y-485500D02*
Y-492500D01*
G01X-1175817Y-485500D02*
X-1171983D01*
G01X-1168767D02*
Y-492500D01*
X-1165433D01*
G01X-1158633D02*
X-1161967D01*
Y-485500D01*
X-1158633D01*
G01X-1159967Y-488883D02*
X-1161967D01*
G01X-916667Y-570000D02*
Y-563000D01*
X-914583D01*
X-913917Y-563350D01*
X-913500Y-563817D01*
X-913333Y-564750D01*
X-913500Y-565683D01*
X-914000Y-566267D01*
X-914583Y-566617D01*
X-916667D01*
G01X-914583D02*
X-913333Y-570000D01*
G01X-906533D02*
X-909867D01*
Y-563000D01*
X-906533D01*
G01X-907867Y-566383D02*
X-909867D01*
G01X-903483Y-563000D02*
X-901400Y-570000D01*
X-899317Y-563000D01*
G01X-907850Y-451567D02*
X-907183Y-452150D01*
X-906433Y-452500D01*
X-905767D01*
X-905100Y-452150D01*
X-904600Y-451567D01*
X-904350Y-450750D01*
X-904517Y-449933D01*
X-904933Y-449233D01*
X-905683Y-448767D01*
X-906683Y-448533D01*
X-907267Y-448067D01*
X-907517Y-447250D01*
X-907350Y-446433D01*
X-906933Y-445850D01*
X-906350Y-445500D01*
X-905767D01*
X-905183Y-445733D01*
X-904683Y-446317D01*
G01X-897467Y-446083D02*
X-897967Y-445733D01*
X-898550Y-445500D01*
X-899217D01*
X-899967Y-445850D01*
X-900550Y-446433D01*
X-900967Y-447133D01*
X-901300Y-448300D01*
X-901383Y-449350D01*
X-901217Y-450400D01*
X-900967Y-451100D01*
X-900467Y-451800D01*
X-899883Y-452267D01*
X-899300Y-452500D01*
X-898717D01*
X-898133Y-452267D01*
X-897633Y-451917D01*
X-897217Y-451450D01*
G01X-894583Y-452500D02*
X-892500Y-445500D01*
X-890417Y-452500D01*
G01X-891167Y-450050D02*
X-893833D01*
G01X-887367Y-445500D02*
Y-452500D01*
X-884033D01*
G01X-877233D02*
X-880567D01*
Y-445500D01*
X-877233D01*
G01X-878567Y-448883D02*
X-880567D01*
G01X-874333Y-572500D02*
Y-565500D01*
X-872667D01*
X-872000Y-565850D01*
X-871500Y-566317D01*
X-871083Y-567017D01*
X-870750Y-567833D01*
X-870667Y-569000D01*
X-870750Y-570167D01*
X-871083Y-570983D01*
X-871500Y-571684D01*
X-872000Y-572150D01*
X-872667Y-572500D01*
X-874333D01*
G01X-866700Y-565500D02*
X-864700D01*
G01X-865700D02*
Y-572500D01*
G01X-866700D02*
X-864700D01*
G01X-860650Y-571567D02*
X-859983Y-572150D01*
X-859233Y-572500D01*
X-858567D01*
X-857900Y-572150D01*
X-857400Y-571567D01*
X-857150Y-570750D01*
X-857317Y-569933D01*
X-857733Y-569233D01*
X-858483Y-568767D01*
X-859483Y-568533D01*
X-860067Y-568067D01*
X-860317Y-567250D01*
X-860150Y-566433D01*
X-859733Y-565850D01*
X-859150Y-565500D01*
X-858567D01*
X-857983Y-565733D01*
X-857483Y-566317D01*
G01X-850267Y-566083D02*
X-850767Y-565733D01*
X-851350Y-565500D01*
X-852017D01*
X-852767Y-565850D01*
X-853350Y-566433D01*
X-853767Y-567133D01*
X-854100Y-568300D01*
X-854183Y-569350D01*
X-854017Y-570400D01*
X-853767Y-571100D01*
X-853267Y-571800D01*
X-852683Y-572267D01*
X-852100Y-572500D01*
X-851517D01*
X-850933Y-572267D01*
X-850433Y-571917D01*
X-850017Y-571450D01*
G01X-846967Y-565500D02*
Y-572500D01*
X-843633D01*
G01X-838500D02*
X-839167Y-572383D01*
X-839750Y-571917D01*
X-840250Y-571217D01*
X-840583Y-570400D01*
X-840750Y-569467D01*
Y-568533D01*
X-840583Y-567600D01*
X-840250Y-566783D01*
X-839750Y-566083D01*
X-839167Y-565617D01*
X-838500Y-565500D01*
X-837833Y-565617D01*
X-837250Y-566083D01*
X-836750Y-566783D01*
X-836417Y-567600D01*
X-836250Y-568533D01*
Y-569467D01*
X-836417Y-570400D01*
X-836750Y-571217D01*
X-837250Y-571917D01*
X-837833Y-572383D01*
X-838500Y-572500D01*
G01X-833450Y-571567D02*
X-832783Y-572150D01*
X-832033Y-572500D01*
X-831367D01*
X-830700Y-572150D01*
X-830200Y-571567D01*
X-829950Y-570750D01*
X-830117Y-569933D01*
X-830533Y-569233D01*
X-831283Y-568767D01*
X-832283Y-568533D01*
X-832867Y-568067D01*
X-833117Y-567250D01*
X-832950Y-566433D01*
X-832533Y-565850D01*
X-831950Y-565500D01*
X-831367D01*
X-830783Y-565733D01*
X-830283Y-566317D01*
G01X-823233Y-572500D02*
X-826567D01*
Y-565500D01*
X-823233D01*
G01X-824567Y-568883D02*
X-826567D01*
G01X-819933Y-572500D02*
Y-565500D01*
X-818267D01*
X-817600Y-565850D01*
X-817100Y-566317D01*
X-816683Y-567017D01*
X-816350Y-567833D01*
X-816267Y-569000D01*
X-816350Y-570167D01*
X-816683Y-570983D01*
X-817100Y-571684D01*
X-817600Y-572150D01*
X-818267Y-572500D01*
X-819933D01*
G01X-807000Y-565500D02*
X-805833Y-572500D01*
X-804500Y-565500D01*
X-803167Y-572500D01*
X-802000Y-565500D01*
G01X-798700D02*
X-796700D01*
G01X-797700D02*
Y-572500D01*
G01X-798700D02*
X-796700D01*
G01X-790900Y-565500D02*
Y-572500D01*
G01X-792817Y-565500D02*
X-788983D01*
G01X-785850Y-572500D02*
Y-565500D01*
G01X-782350D02*
Y-572500D01*
G01Y-569000D02*
X-785850D01*
G01X-777300Y-572500D02*
X-777967Y-572383D01*
X-778550Y-571917D01*
X-779050Y-571217D01*
X-779383Y-570400D01*
X-779550Y-569467D01*
Y-568533D01*
X-779383Y-567600D01*
X-779050Y-566783D01*
X-778550Y-566083D01*
X-777967Y-565617D01*
X-777300Y-565500D01*
X-776633Y-565617D01*
X-776050Y-566083D01*
X-775550Y-566783D01*
X-775217Y-567600D01*
X-775050Y-568533D01*
Y-569467D01*
X-775217Y-570400D01*
X-775550Y-571217D01*
X-776050Y-571917D01*
X-776633Y-572383D01*
X-777300Y-572500D01*
G01X-772333Y-565500D02*
Y-570517D01*
X-772000Y-571567D01*
X-771333Y-572267D01*
X-770500Y-572500D01*
X-769667Y-572267D01*
X-769000Y-571567D01*
X-768667Y-570517D01*
Y-565500D01*
G01X-763700D02*
Y-572500D01*
G01X-765617Y-565500D02*
X-761783D01*
G01X-750100D02*
Y-572500D01*
G01X-752017Y-565500D02*
X-748183D01*
G01X-745050Y-572500D02*
Y-565500D01*
G01X-741550D02*
Y-572500D01*
G01Y-569000D02*
X-745050D01*
G01X-734833Y-572500D02*
X-738167D01*
Y-565500D01*
X-734833D01*
G01X-736167Y-568883D02*
X-738167D01*
G01X-724567Y-572500D02*
Y-565500D01*
X-722567D01*
X-721900Y-565850D01*
X-721400Y-566667D01*
X-721233Y-567600D01*
X-721400Y-568533D01*
X-721817Y-569233D01*
X-722567Y-569584D01*
X-724567D01*
G01X-717767Y-572500D02*
Y-565500D01*
X-715683D01*
X-715017Y-565850D01*
X-714600Y-566317D01*
X-714433Y-567250D01*
X-714600Y-568183D01*
X-715100Y-568767D01*
X-715683Y-569117D01*
X-717767D01*
G01X-715683D02*
X-714433Y-572500D01*
G01X-710300Y-565500D02*
X-708300D01*
G01X-709300D02*
Y-572500D01*
G01X-710300D02*
X-708300D01*
G01X-702500D02*
X-703167Y-572383D01*
X-703750Y-571917D01*
X-704250Y-571217D01*
X-704583Y-570400D01*
X-704750Y-569467D01*
Y-568533D01*
X-704583Y-567600D01*
X-704250Y-566783D01*
X-703750Y-566083D01*
X-703167Y-565617D01*
X-702500Y-565500D01*
X-701833Y-565617D01*
X-701250Y-566083D01*
X-700750Y-566783D01*
X-700417Y-567600D01*
X-700250Y-568533D01*
Y-569467D01*
X-700417Y-570400D01*
X-700750Y-571217D01*
X-701250Y-571917D01*
X-701833Y-572383D01*
X-702500Y-572500D01*
G01X-697367D02*
Y-565500D01*
X-695283D01*
X-694617Y-565850D01*
X-694200Y-566317D01*
X-694033Y-567250D01*
X-694200Y-568183D01*
X-694700Y-568767D01*
X-695283Y-569117D01*
X-697367D01*
G01X-695283D02*
X-694033Y-572500D01*
G01X-684600Y-565500D02*
X-683433Y-572500D01*
X-682100Y-565500D01*
X-680767Y-572500D01*
X-679600Y-565500D01*
G01X-676967Y-572500D02*
Y-565500D01*
X-674883D01*
X-674217Y-565850D01*
X-673800Y-566317D01*
X-673633Y-567250D01*
X-673800Y-568183D01*
X-674300Y-568767D01*
X-674883Y-569117D01*
X-676967D01*
G01X-674883D02*
X-673633Y-572500D01*
G01X-669500Y-565500D02*
X-667500D01*
G01X-668500D02*
Y-572500D01*
G01X-669500D02*
X-667500D01*
G01X-661700Y-565500D02*
Y-572500D01*
G01X-663617Y-565500D02*
X-659783D01*
G01X-654900D02*
Y-572500D01*
G01X-656817Y-565500D02*
X-652983D01*
G01X-646433Y-572500D02*
X-649767D01*
Y-565500D01*
X-646433D01*
G01X-647767Y-568883D02*
X-649767D01*
G01X-643217Y-572500D02*
Y-565500D01*
X-639383Y-572500D01*
Y-565500D01*
G01X-625867Y-566083D02*
X-626367Y-565733D01*
X-626950Y-565500D01*
X-627617D01*
X-628367Y-565850D01*
X-628950Y-566433D01*
X-629367Y-567133D01*
X-629700Y-568300D01*
X-629783Y-569350D01*
X-629617Y-570400D01*
X-629367Y-571100D01*
X-628867Y-571800D01*
X-628283Y-572267D01*
X-627700Y-572500D01*
X-627117D01*
X-626533Y-572267D01*
X-626033Y-571917D01*
X-625617Y-571450D01*
G01X-620900Y-572500D02*
X-621567Y-572383D01*
X-622150Y-571917D01*
X-622650Y-571217D01*
X-622983Y-570400D01*
X-623150Y-569467D01*
Y-568533D01*
X-622983Y-567600D01*
X-622650Y-566783D01*
X-622150Y-566083D01*
X-621567Y-565617D01*
X-620900Y-565500D01*
X-620233Y-565617D01*
X-619650Y-566083D01*
X-619150Y-566783D01*
X-618817Y-567600D01*
X-618650Y-568533D01*
Y-569467D01*
X-618817Y-570400D01*
X-619150Y-571217D01*
X-619650Y-571917D01*
X-620233Y-572383D01*
X-620900Y-572500D01*
G01X-616017D02*
Y-565500D01*
X-612183Y-572500D01*
Y-565500D01*
G01X-609050Y-571567D02*
X-608383Y-572150D01*
X-607633Y-572500D01*
X-606967D01*
X-606300Y-572150D01*
X-605800Y-571567D01*
X-605550Y-570750D01*
X-605717Y-569933D01*
X-606133Y-569233D01*
X-606883Y-568767D01*
X-607883Y-568533D01*
X-608467Y-568067D01*
X-608717Y-567250D01*
X-608550Y-566433D01*
X-608133Y-565850D01*
X-607550Y-565500D01*
X-606967D01*
X-606383Y-565733D01*
X-605883Y-566317D01*
G01X-598833Y-572500D02*
X-602167D01*
Y-565500D01*
X-598833D01*
G01X-600167Y-568883D02*
X-602167D01*
G01X-595617Y-572500D02*
Y-565500D01*
X-591783Y-572500D01*
Y-565500D01*
G01X-586900D02*
Y-572500D01*
G01X-588817Y-565500D02*
X-584983D01*
G01X-872500Y-587500D02*
X-873167Y-587383D01*
X-873750Y-586917D01*
X-874250Y-586217D01*
X-874583Y-585400D01*
X-874750Y-584467D01*
Y-583533D01*
X-874583Y-582600D01*
X-874250Y-581783D01*
X-873750Y-581083D01*
X-873167Y-580617D01*
X-872500Y-580500D01*
X-871833Y-580617D01*
X-871250Y-581083D01*
X-870750Y-581783D01*
X-870417Y-582600D01*
X-870250Y-583533D01*
Y-584467D01*
X-870417Y-585400D01*
X-870750Y-586217D01*
X-871250Y-586917D01*
X-871833Y-587383D01*
X-872500Y-587500D01*
G01X-867283D02*
Y-580500D01*
X-864117D01*
G01X-865283Y-583883D02*
X-867283D01*
G01X-854267Y-587500D02*
Y-580500D01*
X-852100Y-586333D01*
X-849933Y-580500D01*
Y-587500D01*
G01X-846300Y-580500D02*
X-844300D01*
G01X-845300D02*
Y-587500D01*
G01X-846300D02*
X-844300D01*
G01X-836667Y-581083D02*
X-837167Y-580733D01*
X-837750Y-580500D01*
X-838417D01*
X-839167Y-580850D01*
X-839750Y-581433D01*
X-840167Y-582133D01*
X-840500Y-583300D01*
X-840583Y-584350D01*
X-840417Y-585400D01*
X-840167Y-586100D01*
X-839667Y-586800D01*
X-839083Y-587267D01*
X-838500Y-587500D01*
X-837917D01*
X-837333Y-587267D01*
X-836833Y-586917D01*
X-836417Y-586450D01*
G01X-833367Y-587500D02*
Y-580500D01*
X-831283D01*
X-830617Y-580850D01*
X-830200Y-581317D01*
X-830033Y-582250D01*
X-830200Y-583183D01*
X-830700Y-583767D01*
X-831283Y-584117D01*
X-833367D01*
G01X-831283D02*
X-830033Y-587500D01*
G01X-824900D02*
X-825567Y-587383D01*
X-826150Y-586917D01*
X-826650Y-586217D01*
X-826983Y-585400D01*
X-827150Y-584467D01*
Y-583533D01*
X-826983Y-582600D01*
X-826650Y-581783D01*
X-826150Y-581083D01*
X-825567Y-580617D01*
X-824900Y-580500D01*
X-824233Y-580617D01*
X-823650Y-581083D01*
X-823150Y-581783D01*
X-822817Y-582600D01*
X-822650Y-583533D01*
Y-584467D01*
X-822817Y-585400D01*
X-823150Y-586217D01*
X-823650Y-586917D01*
X-824233Y-587383D01*
X-824900Y-587500D01*
G01X-819850Y-586567D02*
X-819183Y-587150D01*
X-818433Y-587500D01*
X-817767D01*
X-817100Y-587150D01*
X-816600Y-586567D01*
X-816350Y-585750D01*
X-816517Y-584933D01*
X-816933Y-584233D01*
X-817683Y-583767D01*
X-818683Y-583533D01*
X-819267Y-583067D01*
X-819517Y-582250D01*
X-819350Y-581433D01*
X-818933Y-580850D01*
X-818350Y-580500D01*
X-817767D01*
X-817183Y-580733D01*
X-816683Y-581317D01*
G01X-811300Y-587500D02*
X-811967Y-587383D01*
X-812550Y-586917D01*
X-813050Y-586217D01*
X-813383Y-585400D01*
X-813550Y-584467D01*
Y-583533D01*
X-813383Y-582600D01*
X-813050Y-581783D01*
X-812550Y-581083D01*
X-811967Y-580617D01*
X-811300Y-580500D01*
X-810633Y-580617D01*
X-810050Y-581083D01*
X-809550Y-581783D01*
X-809217Y-582600D01*
X-809050Y-583533D01*
Y-584467D01*
X-809217Y-585400D01*
X-809550Y-586217D01*
X-810050Y-586917D01*
X-810633Y-587383D01*
X-811300Y-587500D01*
G01X-806083D02*
Y-580500D01*
X-802917D01*
G01X-804083Y-583883D02*
X-806083D01*
G01X-797700Y-580500D02*
Y-587500D01*
G01X-799617Y-580500D02*
X-795783D01*
G01X-782267Y-581083D02*
X-782767Y-580733D01*
X-783350Y-580500D01*
X-784017D01*
X-784767Y-580850D01*
X-785350Y-581433D01*
X-785767Y-582133D01*
X-786100Y-583300D01*
X-786183Y-584350D01*
X-786017Y-585400D01*
X-785767Y-586100D01*
X-785267Y-586800D01*
X-784683Y-587267D01*
X-784100Y-587500D01*
X-783517D01*
X-782933Y-587267D01*
X-782433Y-586917D01*
X-782017Y-586450D01*
G01X-777300Y-587500D02*
X-777967Y-587383D01*
X-778550Y-586917D01*
X-779050Y-586217D01*
X-779383Y-585400D01*
X-779550Y-584467D01*
Y-583533D01*
X-779383Y-582600D01*
X-779050Y-581783D01*
X-778550Y-581083D01*
X-777967Y-580617D01*
X-777300Y-580500D01*
X-776633Y-580617D01*
X-776050Y-581083D01*
X-775550Y-581783D01*
X-775217Y-582600D01*
X-775050Y-583533D01*
Y-584467D01*
X-775217Y-585400D01*
X-775550Y-586217D01*
X-776050Y-586917D01*
X-776633Y-587383D01*
X-777300Y-587500D01*
G01X-772167D02*
Y-580500D01*
X-770083D01*
X-769417Y-580850D01*
X-769000Y-581317D01*
X-768833Y-582250D01*
X-769000Y-583183D01*
X-769500Y-583767D01*
X-770083Y-584117D01*
X-772167D01*
G01X-770083D02*
X-768833Y-587500D01*
G01X-765367D02*
Y-580500D01*
X-763367D01*
X-762700Y-580850D01*
X-762200Y-581667D01*
X-762033Y-582600D01*
X-762200Y-583533D01*
X-762617Y-584233D01*
X-763367Y-584584D01*
X-765367D01*
G01X-756900Y-587500D02*
X-757567Y-587383D01*
X-758150Y-586917D01*
X-758650Y-586217D01*
X-758983Y-585400D01*
X-759150Y-584467D01*
Y-583533D01*
X-758983Y-582600D01*
X-758650Y-581783D01*
X-758150Y-581083D01*
X-757567Y-580617D01*
X-756900Y-580500D01*
X-756233Y-580617D01*
X-755650Y-581083D01*
X-755150Y-581783D01*
X-754817Y-582600D01*
X-754650Y-583533D01*
Y-584467D01*
X-754817Y-585400D01*
X-755150Y-586217D01*
X-755650Y-586917D01*
X-756233Y-587383D01*
X-756900Y-587500D01*
G01X-751767D02*
Y-580500D01*
X-749683D01*
X-749017Y-580850D01*
X-748600Y-581317D01*
X-748433Y-582250D01*
X-748600Y-583183D01*
X-749100Y-583767D01*
X-749683Y-584117D01*
X-751767D01*
G01X-749683D02*
X-748433Y-587500D01*
G01X-745383D02*
X-743300Y-580500D01*
X-741217Y-587500D01*
G01X-741967Y-585050D02*
X-744633D01*
G01X-736500Y-580500D02*
Y-587500D01*
G01X-738417Y-580500D02*
X-734583D01*
G01X-730700D02*
X-728700D01*
G01X-729700D02*
Y-587500D01*
G01X-730700D02*
X-728700D01*
G01X-722900D02*
X-723567Y-587383D01*
X-724150Y-586917D01*
X-724650Y-586217D01*
X-724983Y-585400D01*
X-725150Y-584467D01*
Y-583533D01*
X-724983Y-582600D01*
X-724650Y-581783D01*
X-724150Y-581083D01*
X-723567Y-580617D01*
X-722900Y-580500D01*
X-722233Y-580617D01*
X-721650Y-581083D01*
X-721150Y-581783D01*
X-720817Y-582600D01*
X-720650Y-583533D01*
Y-584467D01*
X-720817Y-585400D01*
X-721150Y-586217D01*
X-721650Y-586917D01*
X-722233Y-587383D01*
X-722900Y-587500D01*
G01X-718017D02*
Y-580500D01*
X-714183Y-587500D01*
Y-580500D01*
G01X-709300Y-587733D02*
X-709467Y-587617D01*
Y-587383D01*
X-709300Y-587267D01*
X-709133Y-587383D01*
Y-587617D01*
X-709300Y-587733D01*
G01X-870667Y-551083D02*
X-871167Y-550733D01*
X-871750Y-550500D01*
X-872417D01*
X-873167Y-550850D01*
X-873750Y-551433D01*
X-874167Y-552133D01*
X-874500Y-553300D01*
X-874583Y-554350D01*
X-874417Y-555400D01*
X-874167Y-556100D01*
X-873667Y-556800D01*
X-873083Y-557267D01*
X-872500Y-557500D01*
X-871917D01*
X-871333Y-557267D01*
X-870833Y-556917D01*
X-870417Y-556450D01*
G01X-865700Y-557500D02*
X-866367Y-557383D01*
X-866950Y-556917D01*
X-867450Y-556217D01*
X-867783Y-555400D01*
X-867950Y-554467D01*
Y-553533D01*
X-867783Y-552600D01*
X-867450Y-551783D01*
X-866950Y-551083D01*
X-866367Y-550617D01*
X-865700Y-550500D01*
X-865033Y-550617D01*
X-864450Y-551083D01*
X-863950Y-551783D01*
X-863617Y-552600D01*
X-863450Y-553533D01*
Y-554467D01*
X-863617Y-555400D01*
X-863950Y-556217D01*
X-864450Y-556917D01*
X-865033Y-557383D01*
X-865700Y-557500D01*
G01X-860817D02*
Y-550500D01*
X-856983Y-557500D01*
Y-550500D01*
G01X-853683Y-557500D02*
Y-550500D01*
X-850517D01*
G01X-851683Y-553883D02*
X-853683D01*
G01X-846300Y-550500D02*
X-844300D01*
G01X-845300D02*
Y-557500D01*
G01X-846300D02*
X-844300D01*
G01X-840333D02*
Y-550500D01*
X-838667D01*
X-838000Y-550850D01*
X-837500Y-551317D01*
X-837083Y-552017D01*
X-836750Y-552833D01*
X-836667Y-554000D01*
X-836750Y-555167D01*
X-837083Y-555983D01*
X-837500Y-556684D01*
X-838000Y-557150D01*
X-838667Y-557500D01*
X-840333D01*
G01X-830033D02*
X-833367D01*
Y-550500D01*
X-830033D01*
G01X-831367Y-553883D02*
X-833367D01*
G01X-826817Y-557500D02*
Y-550500D01*
X-822983Y-557500D01*
Y-550500D01*
G01X-816267Y-551083D02*
X-816767Y-550733D01*
X-817350Y-550500D01*
X-818017D01*
X-818767Y-550850D01*
X-819350Y-551433D01*
X-819767Y-552133D01*
X-820100Y-553300D01*
X-820183Y-554350D01*
X-820017Y-555400D01*
X-819767Y-556100D01*
X-819267Y-556800D01*
X-818683Y-557267D01*
X-818100Y-557500D01*
X-817517D01*
X-816933Y-557267D01*
X-816433Y-556917D01*
X-816017Y-556450D01*
G01X-809633Y-557500D02*
X-812967D01*
Y-550500D01*
X-809633D01*
G01X-810967Y-553883D02*
X-812967D01*
G01X-799783Y-557500D02*
X-797700Y-550500D01*
X-795617Y-557500D01*
G01X-796367Y-555050D02*
X-799033D01*
G01X-792817Y-557500D02*
Y-550500D01*
X-788983Y-557500D01*
Y-550500D01*
G01X-785933Y-557500D02*
Y-550500D01*
X-784267D01*
X-783600Y-550850D01*
X-783100Y-551317D01*
X-782683Y-552017D01*
X-782350Y-552833D01*
X-782267Y-554000D01*
X-782350Y-555167D01*
X-782683Y-555983D01*
X-783100Y-556684D01*
X-783600Y-557150D01*
X-784267Y-557500D01*
X-785933D01*
G01X-771500Y-550500D02*
X-769500D01*
G01X-770500D02*
Y-557500D01*
G01X-771500D02*
X-769500D01*
G01X-763700Y-550500D02*
Y-557500D01*
G01X-765617Y-550500D02*
X-761783D01*
G01X-758650Y-556567D02*
X-757983Y-557150D01*
X-757233Y-557500D01*
X-756567D01*
X-755900Y-557150D01*
X-755400Y-556567D01*
X-755150Y-555750D01*
X-755317Y-554933D01*
X-755733Y-554233D01*
X-756483Y-553767D01*
X-757483Y-553533D01*
X-758067Y-553067D01*
X-758317Y-552250D01*
X-758150Y-551433D01*
X-757733Y-550850D01*
X-757150Y-550500D01*
X-756567D01*
X-755983Y-550733D01*
X-755483Y-551317D01*
G01X-741467Y-551083D02*
X-741967Y-550733D01*
X-742550Y-550500D01*
X-743217D01*
X-743967Y-550850D01*
X-744550Y-551433D01*
X-744967Y-552133D01*
X-745300Y-553300D01*
X-745383Y-554350D01*
X-745217Y-555400D01*
X-744967Y-556100D01*
X-744467Y-556800D01*
X-743883Y-557267D01*
X-743300Y-557500D01*
X-742717D01*
X-742133Y-557267D01*
X-741633Y-556917D01*
X-741217Y-556450D01*
G01X-736500Y-557500D02*
X-737167Y-557383D01*
X-737750Y-556917D01*
X-738250Y-556217D01*
X-738583Y-555400D01*
X-738750Y-554467D01*
Y-553533D01*
X-738583Y-552600D01*
X-738250Y-551783D01*
X-737750Y-551083D01*
X-737167Y-550617D01*
X-736500Y-550500D01*
X-735833Y-550617D01*
X-735250Y-551083D01*
X-734750Y-551783D01*
X-734417Y-552600D01*
X-734250Y-553533D01*
Y-554467D01*
X-734417Y-555400D01*
X-734750Y-556217D01*
X-735250Y-556917D01*
X-735833Y-557383D01*
X-736500Y-557500D01*
G01X-731617D02*
Y-550500D01*
X-727783Y-557500D01*
Y-550500D01*
G01X-722900D02*
Y-557500D01*
G01X-724817Y-550500D02*
X-720983D01*
G01X-714433Y-557500D02*
X-717767D01*
Y-550500D01*
X-714433D01*
G01X-715767Y-553883D02*
X-717767D01*
G01X-711217Y-557500D02*
Y-550500D01*
X-707383Y-557500D01*
Y-550500D01*
G01X-702500D02*
Y-557500D01*
G01X-704417Y-550500D02*
X-700583D01*
G01X-697450Y-556567D02*
X-696783Y-557150D01*
X-696033Y-557500D01*
X-695367D01*
X-694700Y-557150D01*
X-694200Y-556567D01*
X-693950Y-555750D01*
X-694117Y-554933D01*
X-694533Y-554233D01*
X-695283Y-553767D01*
X-696283Y-553533D01*
X-696867Y-553067D01*
X-697117Y-552250D01*
X-696950Y-551433D01*
X-696533Y-550850D01*
X-695950Y-550500D01*
X-695367D01*
X-694783Y-550733D01*
X-694283Y-551317D01*
G01X-684267Y-557500D02*
Y-550500D01*
X-682100Y-556333D01*
X-679933Y-550500D01*
Y-557500D01*
G01X-677383D02*
X-675300Y-550500D01*
X-673217Y-557500D01*
G01X-673967Y-555050D02*
X-676633D01*
G01X-668500Y-557500D02*
Y-554350D01*
X-670167Y-550500D01*
G01X-666833D02*
X-668500Y-554350D01*
G01X-656817Y-557500D02*
Y-550500D01*
X-652983Y-557500D01*
Y-550500D01*
G01X-648100Y-557500D02*
X-648767Y-557383D01*
X-649350Y-556917D01*
X-649850Y-556217D01*
X-650183Y-555400D01*
X-650350Y-554467D01*
Y-553533D01*
X-650183Y-552600D01*
X-649850Y-551783D01*
X-649350Y-551083D01*
X-648767Y-550617D01*
X-648100Y-550500D01*
X-647433Y-550617D01*
X-646850Y-551083D01*
X-646350Y-551783D01*
X-646017Y-552600D01*
X-645850Y-553533D01*
Y-554467D01*
X-646017Y-555400D01*
X-646350Y-556217D01*
X-646850Y-556917D01*
X-647433Y-557383D01*
X-648100Y-557500D01*
G01X-641300Y-550500D02*
Y-557500D01*
G01X-643217Y-550500D02*
X-639383D01*
G01X-627033Y-553767D02*
X-626700Y-553417D01*
X-626450Y-552833D01*
X-626283Y-552017D01*
X-626450Y-551317D01*
X-626783Y-550850D01*
X-627367Y-550500D01*
X-629617D01*
Y-557500D01*
X-626867D01*
X-626283Y-557033D01*
X-625950Y-556333D01*
X-625783Y-555517D01*
X-625950Y-554700D01*
X-626450Y-554000D01*
X-627033Y-553767D01*
X-629617D01*
G01X-619233Y-557500D02*
X-622567D01*
Y-550500D01*
X-619233D01*
G01X-620567Y-553883D02*
X-622567D01*
G01X-870667Y-536083D02*
X-871167Y-535733D01*
X-871750Y-535500D01*
X-872417D01*
X-873167Y-535850D01*
X-873750Y-536433D01*
X-874167Y-537133D01*
X-874500Y-538300D01*
X-874583Y-539350D01*
X-874417Y-540400D01*
X-874167Y-541100D01*
X-873667Y-541800D01*
X-873083Y-542267D01*
X-872500Y-542500D01*
X-871917D01*
X-871333Y-542267D01*
X-870833Y-541917D01*
X-870417Y-541450D01*
G01X-865700Y-542500D02*
X-866367Y-542383D01*
X-866950Y-541917D01*
X-867450Y-541217D01*
X-867783Y-540400D01*
X-867950Y-539467D01*
Y-538533D01*
X-867783Y-537600D01*
X-867450Y-536783D01*
X-866950Y-536083D01*
X-866367Y-535617D01*
X-865700Y-535500D01*
X-865033Y-535617D01*
X-864450Y-536083D01*
X-863950Y-536783D01*
X-863617Y-537600D01*
X-863450Y-538533D01*
Y-539467D01*
X-863617Y-540400D01*
X-863950Y-541217D01*
X-864450Y-541917D01*
X-865033Y-542383D01*
X-865700Y-542500D01*
G01X-860567D02*
Y-535500D01*
X-858483D01*
X-857817Y-535850D01*
X-857400Y-536317D01*
X-857233Y-537250D01*
X-857400Y-538183D01*
X-857900Y-538767D01*
X-858483Y-539117D01*
X-860567D01*
G01X-858483D02*
X-857233Y-542500D01*
G01X-853767D02*
Y-535500D01*
X-851767D01*
X-851100Y-535850D01*
X-850600Y-536667D01*
X-850433Y-537600D01*
X-850600Y-538533D01*
X-851017Y-539233D01*
X-851767Y-539584D01*
X-853767D01*
G01X-845300Y-542500D02*
X-845967Y-542383D01*
X-846550Y-541917D01*
X-847050Y-541217D01*
X-847383Y-540400D01*
X-847550Y-539467D01*
Y-538533D01*
X-847383Y-537600D01*
X-847050Y-536783D01*
X-846550Y-536083D01*
X-845967Y-535617D01*
X-845300Y-535500D01*
X-844633Y-535617D01*
X-844050Y-536083D01*
X-843550Y-536783D01*
X-843217Y-537600D01*
X-843050Y-538533D01*
Y-539467D01*
X-843217Y-540400D01*
X-843550Y-541217D01*
X-844050Y-541917D01*
X-844633Y-542383D01*
X-845300Y-542500D01*
G01X-840167D02*
Y-535500D01*
X-838083D01*
X-837417Y-535850D01*
X-837000Y-536317D01*
X-836833Y-537250D01*
X-837000Y-538183D01*
X-837500Y-538767D01*
X-838083Y-539117D01*
X-840167D01*
G01X-838083D02*
X-836833Y-542500D01*
G01X-833783D02*
X-831700Y-535500D01*
X-829617Y-542500D01*
G01X-830367Y-540050D02*
X-833033D01*
G01X-824900Y-535500D02*
Y-542500D01*
G01X-826817Y-535500D02*
X-822983D01*
G01X-819100D02*
X-817100D01*
G01X-818100D02*
Y-542500D01*
G01X-819100D02*
X-817100D01*
G01X-811300D02*
X-811967Y-542383D01*
X-812550Y-541917D01*
X-813050Y-541217D01*
X-813383Y-540400D01*
X-813550Y-539467D01*
Y-538533D01*
X-813383Y-537600D01*
X-813050Y-536783D01*
X-812550Y-536083D01*
X-811967Y-535617D01*
X-811300Y-535500D01*
X-810633Y-535617D01*
X-810050Y-536083D01*
X-809550Y-536783D01*
X-809217Y-537600D01*
X-809050Y-538533D01*
Y-539467D01*
X-809217Y-540400D01*
X-809550Y-541217D01*
X-810050Y-541917D01*
X-810633Y-542383D01*
X-811300Y-542500D01*
G01X-806417D02*
Y-535500D01*
X-802583Y-542500D01*
Y-535500D01*
G01X-797700Y-542733D02*
X-797867Y-542617D01*
Y-542383D01*
X-797700Y-542267D01*
X-797533Y-542383D01*
Y-542617D01*
X-797700Y-542733D01*
G01X-784100Y-535500D02*
Y-542500D01*
G01X-786017Y-535500D02*
X-782183D01*
G01X-779050Y-542500D02*
Y-535500D01*
G01X-775550D02*
Y-542500D01*
G01Y-539000D02*
X-779050D01*
G01X-771500Y-535500D02*
X-769500D01*
G01X-770500D02*
Y-542500D01*
G01X-771500D02*
X-769500D01*
G01X-765450Y-541567D02*
X-764783Y-542150D01*
X-764033Y-542500D01*
X-763367D01*
X-762700Y-542150D01*
X-762200Y-541567D01*
X-761950Y-540750D01*
X-762117Y-539933D01*
X-762533Y-539233D01*
X-763283Y-538767D01*
X-764283Y-538533D01*
X-764867Y-538067D01*
X-765117Y-537250D01*
X-764950Y-536433D01*
X-764533Y-535850D01*
X-763950Y-535500D01*
X-763367D01*
X-762783Y-535733D01*
X-762283Y-536317D01*
G01X-751933Y-542500D02*
Y-535500D01*
X-750267D01*
X-749600Y-535850D01*
X-749100Y-536317D01*
X-748683Y-537017D01*
X-748350Y-537833D01*
X-748267Y-539000D01*
X-748350Y-540167D01*
X-748683Y-540983D01*
X-749100Y-541684D01*
X-749600Y-542150D01*
X-750267Y-542500D01*
X-751933D01*
G01X-744967D02*
Y-535500D01*
X-742883D01*
X-742217Y-535850D01*
X-741800Y-536317D01*
X-741633Y-537250D01*
X-741800Y-538183D01*
X-742300Y-538767D01*
X-742883Y-539117D01*
X-744967D01*
G01X-742883D02*
X-741633Y-542500D01*
G01X-738583D02*
X-736500Y-535500D01*
X-734417Y-542500D01*
G01X-735167Y-540050D02*
X-737833D01*
G01X-732200Y-535500D02*
X-731033Y-542500D01*
X-729700Y-535500D01*
X-728367Y-542500D01*
X-727200Y-535500D01*
G01X-723900D02*
X-721900D01*
G01X-722900D02*
Y-542500D01*
G01X-723900D02*
X-721900D01*
G01X-718017D02*
Y-535500D01*
X-714183Y-542500D01*
Y-535500D01*
G01X-708800Y-539000D02*
X-707133D01*
Y-541100D01*
X-707633Y-541800D01*
X-708217Y-542267D01*
X-709050Y-542500D01*
X-709883Y-542267D01*
X-710467Y-541800D01*
X-710967Y-541100D01*
X-711300Y-540283D01*
X-711467Y-539350D01*
Y-538533D01*
X-711300Y-537833D01*
X-710967Y-537017D01*
X-710467Y-536317D01*
X-709967Y-535850D01*
X-709300Y-535500D01*
X-708717D01*
X-708050Y-535733D01*
X-707550Y-536200D01*
G01X-696700Y-535500D02*
X-694700D01*
G01X-695700D02*
Y-542500D01*
G01X-696700D02*
X-694700D01*
G01X-690650Y-541567D02*
X-689983Y-542150D01*
X-689233Y-542500D01*
X-688567D01*
X-687900Y-542150D01*
X-687400Y-541567D01*
X-687150Y-540750D01*
X-687317Y-539933D01*
X-687733Y-539233D01*
X-688483Y-538767D01*
X-689483Y-538533D01*
X-690067Y-538067D01*
X-690317Y-537250D01*
X-690150Y-536433D01*
X-689733Y-535850D01*
X-689150Y-535500D01*
X-688567D01*
X-687983Y-535733D01*
X-687483Y-536317D01*
G01X-676967Y-542500D02*
Y-535500D01*
X-674883D01*
X-674217Y-535850D01*
X-673800Y-536317D01*
X-673633Y-537250D01*
X-673800Y-538183D01*
X-674300Y-538767D01*
X-674883Y-539117D01*
X-676967D01*
G01X-674883D02*
X-673633Y-542500D01*
G01X-666833D02*
X-670167D01*
Y-535500D01*
X-666833D01*
G01X-668167Y-538883D02*
X-670167D01*
G01X-659867Y-536083D02*
X-660367Y-535733D01*
X-660950Y-535500D01*
X-661617D01*
X-662367Y-535850D01*
X-662950Y-536433D01*
X-663367Y-537133D01*
X-663700Y-538300D01*
X-663783Y-539350D01*
X-663617Y-540400D01*
X-663367Y-541100D01*
X-662867Y-541800D01*
X-662283Y-542267D01*
X-661700Y-542500D01*
X-661117D01*
X-660533Y-542267D01*
X-660033Y-541917D01*
X-659617Y-541450D01*
G01X-653233Y-542500D02*
X-656567D01*
Y-535500D01*
X-653233D01*
G01X-654567Y-538883D02*
X-656567D01*
G01X-649100Y-535500D02*
X-647100D01*
G01X-648100D02*
Y-542500D01*
G01X-649100D02*
X-647100D01*
G01X-643383Y-535500D02*
X-641300Y-542500D01*
X-639217Y-535500D01*
G01X-632833Y-542500D02*
X-636167D01*
Y-535500D01*
X-632833D01*
G01X-634167Y-538883D02*
X-636167D01*
G01X-629533Y-542500D02*
Y-535500D01*
X-627867D01*
X-627200Y-535850D01*
X-626700Y-536317D01*
X-626283Y-537017D01*
X-625950Y-537833D01*
X-625867Y-539000D01*
X-625950Y-540167D01*
X-626283Y-540983D01*
X-626700Y-541684D01*
X-627200Y-542150D01*
X-627867Y-542500D01*
X-629533D01*
G01X-615100Y-535500D02*
X-613100D01*
G01X-614100D02*
Y-542500D01*
G01X-615100D02*
X-613100D01*
G01X-609217D02*
Y-535500D01*
X-605383Y-542500D01*
Y-535500D01*
G01X-872500Y-520500D02*
Y-527500D01*
G01X-874417Y-520500D02*
X-870583D01*
G01X-867450Y-527500D02*
Y-520500D01*
G01X-863950D02*
Y-527500D01*
G01Y-524000D02*
X-867450D01*
G01X-857233Y-527500D02*
X-860567D01*
Y-520500D01*
X-857233D01*
G01X-858567Y-523883D02*
X-860567D01*
G01X-846967Y-527500D02*
Y-520500D01*
X-844967D01*
X-844300Y-520850D01*
X-843800Y-521667D01*
X-843633Y-522600D01*
X-843800Y-523533D01*
X-844217Y-524233D01*
X-844967Y-524584D01*
X-846967D01*
G01X-840167Y-527500D02*
Y-520500D01*
X-838083D01*
X-837417Y-520850D01*
X-837000Y-521317D01*
X-836833Y-522250D01*
X-837000Y-523183D01*
X-837500Y-523767D01*
X-838083Y-524117D01*
X-840167D01*
G01X-838083D02*
X-836833Y-527500D01*
G01X-831700D02*
X-832367Y-527383D01*
X-832950Y-526917D01*
X-833450Y-526217D01*
X-833783Y-525400D01*
X-833950Y-524467D01*
Y-523533D01*
X-833783Y-522600D01*
X-833450Y-521783D01*
X-832950Y-521083D01*
X-832367Y-520617D01*
X-831700Y-520500D01*
X-831033Y-520617D01*
X-830450Y-521083D01*
X-829950Y-521783D01*
X-829617Y-522600D01*
X-829450Y-523533D01*
Y-524467D01*
X-829617Y-525400D01*
X-829950Y-526217D01*
X-830450Y-526917D01*
X-831033Y-527383D01*
X-831700Y-527500D01*
G01X-826567D02*
Y-520500D01*
X-824567D01*
X-823900Y-520850D01*
X-823400Y-521667D01*
X-823233Y-522600D01*
X-823400Y-523533D01*
X-823817Y-524233D01*
X-824567Y-524584D01*
X-826567D01*
G01X-819767Y-527500D02*
Y-520500D01*
X-817683D01*
X-817017Y-520850D01*
X-816600Y-521317D01*
X-816433Y-522250D01*
X-816600Y-523183D01*
X-817100Y-523767D01*
X-817683Y-524117D01*
X-819767D01*
G01X-817683D02*
X-816433Y-527500D01*
G01X-812300Y-520500D02*
X-810300D01*
G01X-811300D02*
Y-527500D01*
G01X-812300D02*
X-810300D01*
G01X-802833D02*
X-806167D01*
Y-520500D01*
X-802833D01*
G01X-804167Y-523883D02*
X-806167D01*
G01X-797700Y-520500D02*
Y-527500D01*
G01X-799617Y-520500D02*
X-795783D01*
G01X-792983Y-527500D02*
X-790900Y-520500D01*
X-788817Y-527500D01*
G01X-789567Y-525050D02*
X-792233D01*
G01X-785767Y-527500D02*
Y-520500D01*
X-783683D01*
X-783017Y-520850D01*
X-782600Y-521317D01*
X-782433Y-522250D01*
X-782600Y-523183D01*
X-783100Y-523767D01*
X-783683Y-524117D01*
X-785767D01*
G01X-783683D02*
X-782433Y-527500D01*
G01X-777300D02*
Y-524350D01*
X-778967Y-520500D01*
G01X-775633D02*
X-777300Y-524350D01*
G01X-765367Y-527500D02*
Y-520500D01*
X-763367D01*
X-762700Y-520850D01*
X-762200Y-521667D01*
X-762033Y-522600D01*
X-762200Y-523533D01*
X-762617Y-524233D01*
X-763367Y-524584D01*
X-765367D01*
G01X-758567Y-527500D02*
Y-520500D01*
X-756483D01*
X-755817Y-520850D01*
X-755400Y-521317D01*
X-755233Y-522250D01*
X-755400Y-523183D01*
X-755900Y-523767D01*
X-756483Y-524117D01*
X-758567D01*
G01X-756483D02*
X-755233Y-527500D01*
G01X-750100D02*
X-750767Y-527383D01*
X-751350Y-526917D01*
X-751850Y-526217D01*
X-752183Y-525400D01*
X-752350Y-524467D01*
Y-523533D01*
X-752183Y-522600D01*
X-751850Y-521783D01*
X-751350Y-521083D01*
X-750767Y-520617D01*
X-750100Y-520500D01*
X-749433Y-520617D01*
X-748850Y-521083D01*
X-748350Y-521783D01*
X-748017Y-522600D01*
X-747850Y-523533D01*
Y-524467D01*
X-748017Y-525400D01*
X-748350Y-526217D01*
X-748850Y-526917D01*
X-749433Y-527383D01*
X-750100Y-527500D01*
G01X-744967D02*
Y-520500D01*
X-742967D01*
X-742300Y-520850D01*
X-741800Y-521667D01*
X-741633Y-522600D01*
X-741800Y-523533D01*
X-742217Y-524233D01*
X-742967Y-524584D01*
X-744967D01*
G01X-734833Y-527500D02*
X-738167D01*
Y-520500D01*
X-734833D01*
G01X-736167Y-523883D02*
X-738167D01*
G01X-731367Y-527500D02*
Y-520500D01*
X-729283D01*
X-728617Y-520850D01*
X-728200Y-521317D01*
X-728033Y-522250D01*
X-728200Y-523183D01*
X-728700Y-523767D01*
X-729283Y-524117D01*
X-731367D01*
G01X-729283D02*
X-728033Y-527500D01*
G01X-722900Y-520500D02*
Y-527500D01*
G01X-724817Y-520500D02*
X-720983D01*
G01X-716100Y-527500D02*
Y-524350D01*
X-717767Y-520500D01*
G01X-714433D02*
X-716100Y-524350D01*
G01X-702500Y-527500D02*
X-703167Y-527383D01*
X-703750Y-526917D01*
X-704250Y-526217D01*
X-704583Y-525400D01*
X-704750Y-524467D01*
Y-523533D01*
X-704583Y-522600D01*
X-704250Y-521783D01*
X-703750Y-521083D01*
X-703167Y-520617D01*
X-702500Y-520500D01*
X-701833Y-520617D01*
X-701250Y-521083D01*
X-700750Y-521783D01*
X-700417Y-522600D01*
X-700250Y-523533D01*
Y-524467D01*
X-700417Y-525400D01*
X-700750Y-526217D01*
X-701250Y-526917D01*
X-701833Y-527383D01*
X-702500Y-527500D01*
G01X-697283D02*
Y-520500D01*
X-694117D01*
G01X-695283Y-523883D02*
X-697283D01*
G01X-684267Y-527500D02*
Y-520500D01*
X-682100Y-526333D01*
X-679933Y-520500D01*
Y-527500D01*
G01X-676300Y-520500D02*
X-674300D01*
G01X-675300D02*
Y-527500D01*
G01X-676300D02*
X-674300D01*
G01X-666667Y-521083D02*
X-667167Y-520733D01*
X-667750Y-520500D01*
X-668417D01*
X-669167Y-520850D01*
X-669750Y-521433D01*
X-670167Y-522133D01*
X-670500Y-523300D01*
X-670583Y-524350D01*
X-670417Y-525400D01*
X-670167Y-526100D01*
X-669667Y-526800D01*
X-669083Y-527267D01*
X-668500Y-527500D01*
X-667917D01*
X-667333Y-527267D01*
X-666833Y-526917D01*
X-666417Y-526450D01*
G01X-663367Y-527500D02*
Y-520500D01*
X-661283D01*
X-660617Y-520850D01*
X-660200Y-521317D01*
X-660033Y-522250D01*
X-660200Y-523183D01*
X-660700Y-523767D01*
X-661283Y-524117D01*
X-663367D01*
G01X-661283D02*
X-660033Y-527500D01*
G01X-654900D02*
X-655567Y-527383D01*
X-656150Y-526917D01*
X-656650Y-526217D01*
X-656983Y-525400D01*
X-657150Y-524467D01*
Y-523533D01*
X-656983Y-522600D01*
X-656650Y-521783D01*
X-656150Y-521083D01*
X-655567Y-520617D01*
X-654900Y-520500D01*
X-654233Y-520617D01*
X-653650Y-521083D01*
X-653150Y-521783D01*
X-652817Y-522600D01*
X-652650Y-523533D01*
Y-524467D01*
X-652817Y-525400D01*
X-653150Y-526217D01*
X-653650Y-526917D01*
X-654233Y-527383D01*
X-654900Y-527500D01*
G01X-649850Y-526567D02*
X-649183Y-527150D01*
X-648433Y-527500D01*
X-647767D01*
X-647100Y-527150D01*
X-646600Y-526567D01*
X-646350Y-525750D01*
X-646517Y-524933D01*
X-646933Y-524233D01*
X-647683Y-523767D01*
X-648683Y-523533D01*
X-649267Y-523067D01*
X-649517Y-522250D01*
X-649350Y-521433D01*
X-648933Y-520850D01*
X-648350Y-520500D01*
X-647767D01*
X-647183Y-520733D01*
X-646683Y-521317D01*
G01X-641300Y-527500D02*
X-641967Y-527383D01*
X-642550Y-526917D01*
X-643050Y-526217D01*
X-643383Y-525400D01*
X-643550Y-524467D01*
Y-523533D01*
X-643383Y-522600D01*
X-643050Y-521783D01*
X-642550Y-521083D01*
X-641967Y-520617D01*
X-641300Y-520500D01*
X-640633Y-520617D01*
X-640050Y-521083D01*
X-639550Y-521783D01*
X-639217Y-522600D01*
X-639050Y-523533D01*
Y-524467D01*
X-639217Y-525400D01*
X-639550Y-526217D01*
X-640050Y-526917D01*
X-640633Y-527383D01*
X-641300Y-527500D01*
G01X-636083D02*
Y-520500D01*
X-632917D01*
G01X-634083Y-523883D02*
X-636083D01*
G01X-627700Y-520500D02*
Y-527500D01*
G01X-629617Y-520500D02*
X-625783D01*
G01X-872500Y-505500D02*
Y-512500D01*
G01X-874417Y-505500D02*
X-870583D01*
G01X-867450Y-512500D02*
Y-505500D01*
G01X-863950D02*
Y-512500D01*
G01Y-509000D02*
X-867450D01*
G01X-859900Y-505500D02*
X-857900D01*
G01X-858900D02*
Y-512500D01*
G01X-859900D02*
X-857900D01*
G01X-853850Y-511567D02*
X-853183Y-512150D01*
X-852433Y-512500D01*
X-851767D01*
X-851100Y-512150D01*
X-850600Y-511567D01*
X-850350Y-510750D01*
X-850517Y-509933D01*
X-850933Y-509233D01*
X-851683Y-508767D01*
X-852683Y-508533D01*
X-853267Y-508067D01*
X-853517Y-507250D01*
X-853350Y-506433D01*
X-852933Y-505850D01*
X-852350Y-505500D01*
X-851767D01*
X-851183Y-505733D01*
X-850683Y-506317D01*
G01X-840333Y-512500D02*
Y-505500D01*
X-838667D01*
X-838000Y-505850D01*
X-837500Y-506317D01*
X-837083Y-507017D01*
X-836750Y-507833D01*
X-836667Y-509000D01*
X-836750Y-510167D01*
X-837083Y-510983D01*
X-837500Y-511684D01*
X-838000Y-512150D01*
X-838667Y-512500D01*
X-840333D01*
G01X-833367D02*
Y-505500D01*
X-831283D01*
X-830617Y-505850D01*
X-830200Y-506317D01*
X-830033Y-507250D01*
X-830200Y-508183D01*
X-830700Y-508767D01*
X-831283Y-509117D01*
X-833367D01*
G01X-831283D02*
X-830033Y-512500D01*
G01X-826983D02*
X-824900Y-505500D01*
X-822817Y-512500D01*
G01X-823567Y-510050D02*
X-826233D01*
G01X-820600Y-505500D02*
X-819433Y-512500D01*
X-818100Y-505500D01*
X-816767Y-512500D01*
X-815600Y-505500D01*
G01X-812300D02*
X-810300D01*
G01X-811300D02*
Y-512500D01*
G01X-812300D02*
X-810300D01*
G01X-806417D02*
Y-505500D01*
X-802583Y-512500D01*
Y-505500D01*
G01X-797200Y-509000D02*
X-795533D01*
Y-511100D01*
X-796033Y-511800D01*
X-796617Y-512267D01*
X-797450Y-512500D01*
X-798283Y-512267D01*
X-798867Y-511800D01*
X-799367Y-511100D01*
X-799700Y-510283D01*
X-799867Y-509350D01*
Y-508533D01*
X-799700Y-507833D01*
X-799367Y-507017D01*
X-798867Y-506317D01*
X-798367Y-505850D01*
X-797700Y-505500D01*
X-797117D01*
X-796450Y-505733D01*
X-795950Y-506200D01*
G01X-782267Y-506083D02*
X-782767Y-505733D01*
X-783350Y-505500D01*
X-784017D01*
X-784767Y-505850D01*
X-785350Y-506433D01*
X-785767Y-507133D01*
X-786100Y-508300D01*
X-786183Y-509350D01*
X-786017Y-510400D01*
X-785767Y-511100D01*
X-785267Y-511800D01*
X-784683Y-512267D01*
X-784100Y-512500D01*
X-783517D01*
X-782933Y-512267D01*
X-782433Y-511917D01*
X-782017Y-511450D01*
G01X-777300Y-512500D02*
X-777967Y-512383D01*
X-778550Y-511917D01*
X-779050Y-511217D01*
X-779383Y-510400D01*
X-779550Y-509467D01*
Y-508533D01*
X-779383Y-507600D01*
X-779050Y-506783D01*
X-778550Y-506083D01*
X-777967Y-505617D01*
X-777300Y-505500D01*
X-776633Y-505617D01*
X-776050Y-506083D01*
X-775550Y-506783D01*
X-775217Y-507600D01*
X-775050Y-508533D01*
Y-509467D01*
X-775217Y-510400D01*
X-775550Y-511217D01*
X-776050Y-511917D01*
X-776633Y-512383D01*
X-777300Y-512500D01*
G01X-772417D02*
Y-505500D01*
X-768583Y-512500D01*
Y-505500D01*
G01X-763700D02*
Y-512500D01*
G01X-765617Y-505500D02*
X-761783D01*
G01X-758983Y-512500D02*
X-756900Y-505500D01*
X-754817Y-512500D01*
G01X-755567Y-510050D02*
X-758233D01*
G01X-751100Y-505500D02*
X-749100D01*
G01X-750100D02*
Y-512500D01*
G01X-751100D02*
X-749100D01*
G01X-745217D02*
Y-505500D01*
X-741383Y-512500D01*
Y-505500D01*
G01X-738250Y-511567D02*
X-737583Y-512150D01*
X-736833Y-512500D01*
X-736167D01*
X-735500Y-512150D01*
X-735000Y-511567D01*
X-734750Y-510750D01*
X-734917Y-509933D01*
X-735333Y-509233D01*
X-736083Y-508767D01*
X-737083Y-508533D01*
X-737667Y-508067D01*
X-737917Y-507250D01*
X-737750Y-506433D01*
X-737333Y-505850D01*
X-736750Y-505500D01*
X-736167D01*
X-735583Y-505733D01*
X-735083Y-506317D01*
G01X-723900Y-505500D02*
X-721900D01*
G01X-722900D02*
Y-512500D01*
G01X-723900D02*
X-721900D01*
G01X-718017D02*
Y-505500D01*
X-714183Y-512500D01*
Y-505500D01*
G01X-710883Y-512500D02*
Y-505500D01*
X-707717D01*
G01X-708883Y-508883D02*
X-710883D01*
G01X-702500Y-512500D02*
X-703167Y-512383D01*
X-703750Y-511917D01*
X-704250Y-511217D01*
X-704583Y-510400D01*
X-704750Y-509467D01*
Y-508533D01*
X-704583Y-507600D01*
X-704250Y-506783D01*
X-703750Y-506083D01*
X-703167Y-505617D01*
X-702500Y-505500D01*
X-701833Y-505617D01*
X-701250Y-506083D01*
X-700750Y-506783D01*
X-700417Y-507600D01*
X-700250Y-508533D01*
Y-509467D01*
X-700417Y-510400D01*
X-700750Y-511217D01*
X-701250Y-511917D01*
X-701833Y-512383D01*
X-702500Y-512500D01*
G01X-697367D02*
Y-505500D01*
X-695283D01*
X-694617Y-505850D01*
X-694200Y-506317D01*
X-694033Y-507250D01*
X-694200Y-508183D01*
X-694700Y-508767D01*
X-695283Y-509117D01*
X-697367D01*
G01X-695283D02*
X-694033Y-512500D01*
G01X-691067D02*
Y-505500D01*
X-688900Y-511333D01*
X-686733Y-505500D01*
Y-512500D01*
G01X-684183D02*
X-682100Y-505500D01*
X-680017Y-512500D01*
G01X-680767Y-510050D02*
X-683433D01*
G01X-675300Y-505500D02*
Y-512500D01*
G01X-677217Y-505500D02*
X-673383D01*
G01X-669500D02*
X-667500D01*
G01X-668500D02*
Y-512500D01*
G01X-669500D02*
X-667500D01*
G01X-661700D02*
X-662367Y-512383D01*
X-662950Y-511917D01*
X-663450Y-511217D01*
X-663783Y-510400D01*
X-663950Y-509467D01*
Y-508533D01*
X-663783Y-507600D01*
X-663450Y-506783D01*
X-662950Y-506083D01*
X-662367Y-505617D01*
X-661700Y-505500D01*
X-661033Y-505617D01*
X-660450Y-506083D01*
X-659950Y-506783D01*
X-659617Y-507600D01*
X-659450Y-508533D01*
Y-509467D01*
X-659617Y-510400D01*
X-659950Y-511217D01*
X-660450Y-511917D01*
X-661033Y-512383D01*
X-661700Y-512500D01*
G01X-656817D02*
Y-505500D01*
X-652983Y-512500D01*
Y-505500D01*
G01X-643800D02*
X-642633Y-512500D01*
X-641300Y-505500D01*
X-639967Y-512500D01*
X-638800Y-505500D01*
G01X-636250Y-512500D02*
Y-505500D01*
G01X-632750D02*
Y-512500D01*
G01Y-509000D02*
X-636250D01*
G01X-628700Y-505500D02*
X-626700D01*
G01X-627700D02*
Y-512500D01*
G01X-628700D02*
X-626700D01*
G01X-619067Y-506083D02*
X-619567Y-505733D01*
X-620150Y-505500D01*
X-620817D01*
X-621567Y-505850D01*
X-622150Y-506433D01*
X-622567Y-507133D01*
X-622900Y-508300D01*
X-622983Y-509350D01*
X-622817Y-510400D01*
X-622567Y-511100D01*
X-622067Y-511800D01*
X-621483Y-512267D01*
X-620900Y-512500D01*
X-620317D01*
X-619733Y-512267D01*
X-619233Y-511917D01*
X-618817Y-511450D01*
G01X-615850Y-512500D02*
Y-505500D01*
G01X-612350D02*
Y-512500D01*
G01Y-509000D02*
X-615850D01*
G01X-601500Y-505500D02*
X-599500D01*
G01X-600500D02*
Y-512500D01*
G01X-601500D02*
X-599500D01*
G01X-595450Y-511567D02*
X-594783Y-512150D01*
X-594033Y-512500D01*
X-593367D01*
X-592700Y-512150D01*
X-592200Y-511567D01*
X-591950Y-510750D01*
X-592117Y-509933D01*
X-592533Y-509233D01*
X-593283Y-508767D01*
X-594283Y-508533D01*
X-594867Y-508067D01*
X-595117Y-507250D01*
X-594950Y-506433D01*
X-594533Y-505850D01*
X-593950Y-505500D01*
X-593367D01*
X-592783Y-505733D01*
X-592283Y-506317D01*
G01X-858133Y-452500D02*
Y-445500D01*
X-856467D01*
X-855800Y-445850D01*
X-855300Y-446317D01*
X-854883Y-447017D01*
X-854550Y-447833D01*
X-854467Y-449000D01*
X-854550Y-450167D01*
X-854883Y-450983D01*
X-855300Y-451684D01*
X-855800Y-452150D01*
X-856467Y-452500D01*
X-858133D01*
G01X-847833D02*
X-851167D01*
Y-445500D01*
X-847833D01*
G01X-849167Y-448883D02*
X-851167D01*
G01X-844450Y-451567D02*
X-843783Y-452150D01*
X-843033Y-452500D01*
X-842367D01*
X-841700Y-452150D01*
X-841200Y-451567D01*
X-840950Y-450750D01*
X-841117Y-449933D01*
X-841533Y-449233D01*
X-842283Y-448767D01*
X-843283Y-448533D01*
X-843867Y-448067D01*
X-844117Y-447250D01*
X-843950Y-446433D01*
X-843533Y-445850D01*
X-842950Y-445500D01*
X-842367D01*
X-841783Y-445733D01*
X-841283Y-446317D01*
G01X-836900Y-445500D02*
X-834900D01*
G01X-835900D02*
Y-452500D01*
G01X-836900D02*
X-834900D01*
G01X-828600Y-449000D02*
X-826933D01*
Y-451100D01*
X-827433Y-451800D01*
X-828017Y-452267D01*
X-828850Y-452500D01*
X-829683Y-452267D01*
X-830267Y-451800D01*
X-830767Y-451100D01*
X-831100Y-450283D01*
X-831267Y-449350D01*
Y-448533D01*
X-831100Y-447833D01*
X-830767Y-447017D01*
X-830267Y-446317D01*
X-829767Y-445850D01*
X-829100Y-445500D01*
X-828517D01*
X-827850Y-445733D01*
X-827350Y-446200D01*
G01X-824217Y-452500D02*
Y-445500D01*
X-820383Y-452500D01*
Y-445500D01*
G01X-813833Y-452500D02*
X-817167D01*
Y-445500D01*
X-813833D01*
G01X-815167Y-448883D02*
X-817167D01*
G01X-810367Y-452500D02*
Y-445500D01*
X-808283D01*
X-807617Y-445850D01*
X-807200Y-446317D01*
X-807033Y-447250D01*
X-807200Y-448183D01*
X-807700Y-448767D01*
X-808283Y-449117D01*
X-810367D01*
G01X-808283D02*
X-807033Y-452500D01*
G01X-858133D02*
Y-445500D01*
X-856467D01*
X-855800Y-445850D01*
X-855300Y-446317D01*
X-854883Y-447017D01*
X-854550Y-447833D01*
X-854467Y-449000D01*
X-854550Y-450167D01*
X-854883Y-450983D01*
X-855300Y-451684D01*
X-855800Y-452150D01*
X-856467Y-452500D01*
X-858133D01*
G01X-847833D02*
X-851167D01*
Y-445500D01*
X-847833D01*
G01X-849167Y-448883D02*
X-851167D01*
G01X-844450Y-451567D02*
X-843783Y-452150D01*
X-843033Y-452500D01*
X-842367D01*
X-841700Y-452150D01*
X-841200Y-451567D01*
X-840950Y-450750D01*
X-841117Y-449933D01*
X-841533Y-449233D01*
X-842283Y-448767D01*
X-843283Y-448533D01*
X-843867Y-448067D01*
X-844117Y-447250D01*
X-843950Y-446433D01*
X-843533Y-445850D01*
X-842950Y-445500D01*
X-842367D01*
X-841783Y-445733D01*
X-841283Y-446317D01*
G01X-836900Y-445500D02*
X-834900D01*
G01X-835900D02*
Y-452500D01*
G01X-836900D02*
X-834900D01*
G01X-828600Y-449000D02*
X-826933D01*
Y-451100D01*
X-827433Y-451800D01*
X-828017Y-452267D01*
X-828850Y-452500D01*
X-829683Y-452267D01*
X-830267Y-451800D01*
X-830767Y-451100D01*
X-831100Y-450283D01*
X-831267Y-449350D01*
Y-448533D01*
X-831100Y-447833D01*
X-830767Y-447017D01*
X-830267Y-446317D01*
X-829767Y-445850D01*
X-829100Y-445500D01*
X-828517D01*
X-827850Y-445733D01*
X-827350Y-446200D01*
G01X-824217Y-452500D02*
Y-445500D01*
X-820383Y-452500D01*
Y-445500D01*
G01X-813833Y-452500D02*
X-817167D01*
Y-445500D01*
X-813833D01*
G01X-815167Y-448883D02*
X-817167D01*
G01X-810367Y-452500D02*
Y-445500D01*
X-808283D01*
X-807617Y-445850D01*
X-807200Y-446317D01*
X-807033Y-447250D01*
X-807200Y-448183D01*
X-807700Y-448767D01*
X-808283Y-449117D01*
X-810367D01*
G01X-808283D02*
X-807033Y-452500D01*
G01X-642033Y-455000D02*
Y-448000D01*
X-640367D01*
X-639700Y-448350D01*
X-639200Y-448817D01*
X-638783Y-449517D01*
X-638450Y-450333D01*
X-638367Y-451500D01*
X-638450Y-452667D01*
X-638783Y-453483D01*
X-639200Y-454184D01*
X-639700Y-454650D01*
X-640367Y-455000D01*
X-642033D01*
G01X-635483D02*
X-633400Y-448000D01*
X-631317Y-455000D01*
G01X-632067Y-452550D02*
X-634733D01*
G01X-626600Y-448000D02*
Y-455000D01*
G01X-628517Y-448000D02*
X-624683D01*
G01X-618133Y-455000D02*
X-621467D01*
Y-448000D01*
X-618133D01*
G01X-619467Y-451383D02*
X-621467D01*
M02*
